FILE_TYPE = MACRO_DRAWING;
SET COLOR_WIRE YELLOW;
SET COLOR_PROP ORANGE;
SET COLOR_DOT WHITE;
SET COLOR_ARC YELLOW;
SET COLOR_BODY GREEN;
SET COLOR_NOTE PURPLE;
SET PROP_DISPLAY VALUE;
SET PAGE_NUMBER P68;
FORCEADD Q_CAP..1
(-9000 2075);
FORCEPROP 1 LAST LOCATION C2167
J 0
(-8950 2175);
DISPLAY 0.489362 (-8950 2175);
PAINT SKYBLUE (-8950 2175);
FORCEPROP 2 LAST $SEC 1
J 0
(-8950 2275);
DISPLAY 0.680851 (-8950 2275);
PAINT MONO (-8950 2275);
DISPLAY INVISIBLE (-8950 2275);
FORCEPROP 2 LAST CDS_SEC 1
J 0
(-8950 2275);
DISPLAY 1.021277 (-8950 2275);
DISPLAY INVISIBLE (-8950 2275);
FORCEPROP 1 LASTPIN (-9000 2175) $PN 1
J 0
(-8990 2155);
DISPLAY 0.489362 (-8990 2155);
FORCEPROP 1 LASTPIN (-9000 1975) $PN 2
J 0
(-8990 1955);
DISPLAY 0.489362 (-8990 1955);
FORCEPROP 1 LAST MATERIAL X6S
J 0
(-8950 1975);
DISPLAY 0.489362 (-8950 1975);
PAINT SKYBLUE (-8950 1975);
FORCEPROP 1 LAST TOLERANCE 20%
J 0
(-8950 2025);
DISPLAY 0.489362 (-8950 2025);
PAINT SKYBLUE (-8950 2025);
FORCEPROP 1 LAST VALUE 22UF
J 0
(-8950 2125);
DISPLAY 0.489362 (-8950 2125);
PAINT SKYBLUE (-8950 2125);
FORCEPROP 1 LAST PART_NUMBER CH622KMEB02
J 0
(-8950 1925);
DISPLAY 0.489362 (-8950 1925);
PAINT SKYBLUE (-8950 1925);
FORCEPROP 1 LAST VOLTAGE 4V
J 0
(-8950 2075);
DISPLAY 0.489362 (-8950 2075);
PAINT SKYBLUE (-8950 2075);
FORCEPROP 1 LAST PACK_TYPE C0402
J 0
(-8950 1875);
DISPLAY 0.489362 (-8950 1875);
PAINT SKYBLUE (-8950 1875);
FORCEPROP 2 LAST CDS_LIB pure_quanta
J 0
(-9000 2075);
PAINT MONO (-9000 2075);
DISPLAY INVISIBLE (-9000 2075);
FORCEPROP 1 LAST PATH I1
J 0
(-8950 2225);
DISPLAY 0.978723 (-8950 2225);
PAINT WHITE (-8950 2225);
DISPLAY INVISIBLE (-8950 2225);
FORCEADD Q_CAP..1
(-9000 4475);
FORCEPROP 1 LAST LOCATION C246
J 0
(-8950 4575);
DISPLAY 0.489362 (-8950 4575);
PAINT SKYBLUE (-8950 4575);
FORCEPROP 2 LAST $SEC 1
J 0
(-8950 4675);
DISPLAY 0.680851 (-8950 4675);
PAINT MONO (-8950 4675);
DISPLAY INVISIBLE (-8950 4675);
FORCEPROP 2 LAST CDS_SEC 1
J 0
(-8950 4675);
DISPLAY 1.021277 (-8950 4675);
DISPLAY INVISIBLE (-8950 4675);
FORCEPROP 1 LASTPIN (-9000 4575) $PN 1
J 0
(-8990 4555);
DISPLAY 0.489362 (-8990 4555);
FORCEPROP 1 LASTPIN (-9000 4375) $PN 2
J 0
(-8990 4355);
DISPLAY 0.489362 (-8990 4355);
FORCEPROP 1 LAST MATERIAL X6S
J 0
(-8950 4375);
DISPLAY 0.489362 (-8950 4375);
PAINT SKYBLUE (-8950 4375);
FORCEPROP 1 LAST TOLERANCE 20%
J 0
(-8950 4425);
DISPLAY 0.489362 (-8950 4425);
PAINT SKYBLUE (-8950 4425);
FORCEPROP 1 LAST VALUE 22UF
J 0
(-8950 4525);
DISPLAY 0.489362 (-8950 4525);
PAINT SKYBLUE (-8950 4525);
FORCEPROP 1 LAST PART_NUMBER CH622KMEB02
J 0
(-8950 4325);
DISPLAY 0.489362 (-8950 4325);
PAINT SKYBLUE (-8950 4325);
FORCEPROP 1 LAST VOLTAGE 4V
J 0
(-8950 4475);
DISPLAY 0.489362 (-8950 4475);
PAINT SKYBLUE (-8950 4475);
FORCEPROP 1 LAST PACK_TYPE C0402
J 0
(-8950 4275);
DISPLAY 0.489362 (-8950 4275);
PAINT SKYBLUE (-8950 4275);
FORCEPROP 2 LAST CDS_LIB pure_quanta
J 0
(-9000 4475);
PAINT MONO (-9000 4475);
DISPLAY INVISIBLE (-9000 4475);
FORCEPROP 1 LAST PATH I10
J 0
(-8950 4625);
DISPLAY 0.978723 (-8950 4625);
PAINT WHITE (-8950 4625);
DISPLAY INVISIBLE (-8950 4625);
FORCEADD Q_CAP..1
(-2175 5250);
FORCEPROP 1 LAST LOCATION C2231
J 0
(-2125 5350);
DISPLAY 0.489362 (-2125 5350);
PAINT SKYBLUE (-2125 5350);
FORCEPROP 2 LAST $SEC 1
J 0
(-2125 5450);
DISPLAY 0.680851 (-2125 5450);
PAINT MONO (-2125 5450);
DISPLAY INVISIBLE (-2125 5450);
FORCEPROP 2 LAST CDS_SEC 1
J 0
(-2125 5450);
DISPLAY 1.021277 (-2125 5450);
DISPLAY INVISIBLE (-2125 5450);
FORCEPROP 1 LASTPIN (-2175 5350) $PN 1
J 0
(-2165 5330);
DISPLAY 0.489362 (-2165 5330);
FORCEPROP 1 LASTPIN (-2175 5150) $PN 2
J 0
(-2165 5130);
DISPLAY 0.489362 (-2165 5130);
FORCEPROP 1 LAST MATERIAL X6S
J 0
(-2125 5150);
DISPLAY 0.489362 (-2125 5150);
PAINT SKYBLUE (-2125 5150);
FORCEPROP 1 LAST TOLERANCE 20%
J 0
(-2125 5200);
DISPLAY 0.489362 (-2125 5200);
PAINT SKYBLUE (-2125 5200);
FORCEPROP 1 LAST VALUE 22UF
J 0
(-2125 5300);
DISPLAY 0.489362 (-2125 5300);
PAINT SKYBLUE (-2125 5300);
FORCEPROP 1 LAST PART_NUMBER CH622KMEB02
J 0
(-2125 5100);
DISPLAY 0.489362 (-2125 5100);
PAINT SKYBLUE (-2125 5100);
FORCEPROP 1 LAST VOLTAGE 4V
J 0
(-2125 5250);
DISPLAY 0.489362 (-2125 5250);
PAINT SKYBLUE (-2125 5250);
FORCEPROP 1 LAST PACK_TYPE C0402
J 0
(-2125 5050);
DISPLAY 0.489362 (-2125 5050);
PAINT SKYBLUE (-2125 5050);
FORCEPROP 2 LAST CDS_LIB pure_quanta
J 0
(-2175 5250);
PAINT MONO (-2175 5250);
DISPLAY INVISIBLE (-2175 5250);
FORCEPROP 1 LAST PATH I100
J 0
(-2125 5400);
DISPLAY 0.978723 (-2125 5400);
PAINT WHITE (-2125 5400);
DISPLAY INVISIBLE (-2125 5400);
FORCEADD Q_CAP..1
(-1725 4475);
FORCEPROP 1 LAST LOCATION C2238
J 0
(-1675 4575);
DISPLAY 0.489362 (-1675 4575);
PAINT SKYBLUE (-1675 4575);
FORCEPROP 2 LAST $SEC 1
J 0
(-1675 4675);
DISPLAY 0.680851 (-1675 4675);
PAINT MONO (-1675 4675);
DISPLAY INVISIBLE (-1675 4675);
FORCEPROP 2 LAST CDS_SEC 1
J 0
(-1675 4675);
DISPLAY 1.021277 (-1675 4675);
DISPLAY INVISIBLE (-1675 4675);
FORCEPROP 1 LASTPIN (-1725 4575) $PN 1
J 0
(-1715 4555);
DISPLAY 0.489362 (-1715 4555);
FORCEPROP 1 LASTPIN (-1725 4375) $PN 2
J 0
(-1715 4355);
DISPLAY 0.489362 (-1715 4355);
FORCEPROP 1 LAST MATERIAL X6S
J 0
(-1675 4375);
DISPLAY 0.489362 (-1675 4375);
PAINT SKYBLUE (-1675 4375);
FORCEPROP 1 LAST TOLERANCE 20%
J 0
(-1675 4425);
DISPLAY 0.489362 (-1675 4425);
PAINT SKYBLUE (-1675 4425);
FORCEPROP 1 LAST VALUE 22UF
J 0
(-1675 4525);
DISPLAY 0.489362 (-1675 4525);
PAINT SKYBLUE (-1675 4525);
FORCEPROP 1 LAST PART_NUMBER CH622KMEB02
J 0
(-1675 4325);
DISPLAY 0.489362 (-1675 4325);
PAINT SKYBLUE (-1675 4325);
FORCEPROP 1 LAST VOLTAGE 4V
J 0
(-1675 4475);
DISPLAY 0.489362 (-1675 4475);
PAINT SKYBLUE (-1675 4475);
FORCEPROP 1 LAST PACK_TYPE C0402
J 0
(-1675 4275);
DISPLAY 0.489362 (-1675 4275);
PAINT SKYBLUE (-1675 4275);
FORCEPROP 2 LAST CDS_LIB pure_quanta
J 0
(-1725 4475);
PAINT MONO (-1725 4475);
DISPLAY INVISIBLE (-1725 4475);
FORCEPROP 1 LAST PATH I101
J 0
(-1675 4625);
DISPLAY 0.978723 (-1675 4625);
PAINT WHITE (-1675 4625);
DISPLAY INVISIBLE (-1675 4625);
FORCEADD Q_CAP..1
(-1275 4475);
FORCEPROP 1 LAST LOCATION C2244
J 0
(-1225 4575);
DISPLAY 0.489362 (-1225 4575);
PAINT SKYBLUE (-1225 4575);
FORCEPROP 2 LAST $SEC 1
J 0
(-1225 4675);
DISPLAY 0.680851 (-1225 4675);
PAINT MONO (-1225 4675);
DISPLAY INVISIBLE (-1225 4675);
FORCEPROP 2 LAST CDS_SEC 1
J 0
(-1225 4675);
DISPLAY 1.021277 (-1225 4675);
DISPLAY INVISIBLE (-1225 4675);
FORCEPROP 1 LASTPIN (-1275 4575) $PN 1
J 0
(-1265 4555);
DISPLAY 0.489362 (-1265 4555);
FORCEPROP 1 LASTPIN (-1275 4375) $PN 2
J 0
(-1265 4355);
DISPLAY 0.489362 (-1265 4355);
FORCEPROP 1 LAST MATERIAL X6S
J 0
(-1225 4375);
DISPLAY 0.489362 (-1225 4375);
PAINT SKYBLUE (-1225 4375);
FORCEPROP 1 LAST TOLERANCE 20%
J 0
(-1225 4425);
DISPLAY 0.489362 (-1225 4425);
PAINT SKYBLUE (-1225 4425);
FORCEPROP 1 LAST VALUE 22UF
J 0
(-1225 4525);
DISPLAY 0.489362 (-1225 4525);
PAINT SKYBLUE (-1225 4525);
FORCEPROP 1 LAST PART_NUMBER CH622KMEB02
J 0
(-1225 4325);
DISPLAY 0.489362 (-1225 4325);
PAINT SKYBLUE (-1225 4325);
FORCEPROP 1 LAST VOLTAGE 4V
J 0
(-1225 4475);
DISPLAY 0.489362 (-1225 4475);
PAINT SKYBLUE (-1225 4475);
FORCEPROP 1 LAST PACK_TYPE C0402
J 0
(-1225 4275);
DISPLAY 0.489362 (-1225 4275);
PAINT SKYBLUE (-1225 4275);
FORCEPROP 2 LAST CDS_LIB pure_quanta
J 0
(-1275 4475);
PAINT MONO (-1275 4475);
DISPLAY INVISIBLE (-1275 4475);
FORCEPROP 1 LAST PATH I102
J 0
(-1225 4625);
DISPLAY 0.978723 (-1225 4625);
PAINT WHITE (-1225 4625);
DISPLAY INVISIBLE (-1225 4625);
FORCEADD Q_CAP..1
(-1725 5250);
FORCEPROP 1 LAST LOCATION C2237
J 0
(-1675 5350);
DISPLAY 0.489362 (-1675 5350);
PAINT SKYBLUE (-1675 5350);
FORCEPROP 2 LAST $SEC 1
J 0
(-1675 5450);
DISPLAY 0.680851 (-1675 5450);
PAINT MONO (-1675 5450);
DISPLAY INVISIBLE (-1675 5450);
FORCEPROP 2 LAST CDS_SEC 1
J 0
(-1675 5450);
DISPLAY 1.021277 (-1675 5450);
DISPLAY INVISIBLE (-1675 5450);
FORCEPROP 1 LASTPIN (-1725 5350) $PN 1
J 0
(-1715 5330);
DISPLAY 0.489362 (-1715 5330);
FORCEPROP 1 LASTPIN (-1725 5150) $PN 2
J 0
(-1715 5130);
DISPLAY 0.489362 (-1715 5130);
FORCEPROP 1 LAST MATERIAL X6S
J 0
(-1675 5150);
DISPLAY 0.489362 (-1675 5150);
PAINT SKYBLUE (-1675 5150);
FORCEPROP 1 LAST TOLERANCE 20%
J 0
(-1675 5200);
DISPLAY 0.489362 (-1675 5200);
PAINT SKYBLUE (-1675 5200);
FORCEPROP 1 LAST VALUE 22UF
J 0
(-1675 5300);
DISPLAY 0.489362 (-1675 5300);
PAINT SKYBLUE (-1675 5300);
FORCEPROP 1 LAST PART_NUMBER CH622KMEB02
J 0
(-1675 5100);
DISPLAY 0.489362 (-1675 5100);
PAINT SKYBLUE (-1675 5100);
FORCEPROP 1 LAST VOLTAGE 4V
J 0
(-1675 5250);
DISPLAY 0.489362 (-1675 5250);
PAINT SKYBLUE (-1675 5250);
FORCEPROP 1 LAST PACK_TYPE C0402
J 0
(-1675 5050);
DISPLAY 0.489362 (-1675 5050);
PAINT SKYBLUE (-1675 5050);
FORCEPROP 2 LAST CDS_LIB pure_quanta
J 0
(-1725 5250);
PAINT MONO (-1725 5250);
DISPLAY INVISIBLE (-1725 5250);
FORCEPROP 1 LAST PATH I103
J 0
(-1675 5400);
DISPLAY 0.978723 (-1675 5400);
PAINT WHITE (-1675 5400);
DISPLAY INVISIBLE (-1675 5400);
FORCEADD Q_CAP..1
(-1275 5250);
FORCEPROP 1 LAST LOCATION C2243
J 0
(-1225 5350);
DISPLAY 0.489362 (-1225 5350);
PAINT SKYBLUE (-1225 5350);
FORCEPROP 2 LAST $SEC 1
J 0
(-1225 5450);
DISPLAY 0.680851 (-1225 5450);
PAINT MONO (-1225 5450);
DISPLAY INVISIBLE (-1225 5450);
FORCEPROP 2 LAST CDS_SEC 1
J 0
(-1225 5450);
DISPLAY 1.021277 (-1225 5450);
DISPLAY INVISIBLE (-1225 5450);
FORCEPROP 1 LASTPIN (-1275 5350) $PN 1
J 0
(-1265 5330);
DISPLAY 0.489362 (-1265 5330);
FORCEPROP 1 LASTPIN (-1275 5150) $PN 2
J 0
(-1265 5130);
DISPLAY 0.489362 (-1265 5130);
FORCEPROP 1 LAST MATERIAL X6S
J 0
(-1225 5150);
DISPLAY 0.489362 (-1225 5150);
PAINT SKYBLUE (-1225 5150);
FORCEPROP 1 LAST TOLERANCE 20%
J 0
(-1225 5200);
DISPLAY 0.489362 (-1225 5200);
PAINT SKYBLUE (-1225 5200);
FORCEPROP 1 LAST VALUE 22UF
J 0
(-1225 5300);
DISPLAY 0.489362 (-1225 5300);
PAINT SKYBLUE (-1225 5300);
FORCEPROP 1 LAST PART_NUMBER CH622KMEB02
J 0
(-1225 5100);
DISPLAY 0.489362 (-1225 5100);
PAINT SKYBLUE (-1225 5100);
FORCEPROP 1 LAST VOLTAGE 4V
J 0
(-1225 5250);
DISPLAY 0.489362 (-1225 5250);
PAINT SKYBLUE (-1225 5250);
FORCEPROP 1 LAST PACK_TYPE C0402
J 0
(-1225 5050);
DISPLAY 0.489362 (-1225 5050);
PAINT SKYBLUE (-1225 5050);
FORCEPROP 2 LAST CDS_LIB pure_quanta
J 0
(-1275 5250);
PAINT MONO (-1275 5250);
DISPLAY INVISIBLE (-1275 5250);
FORCEPROP 1 LAST PATH I104
J 0
(-1225 5400);
DISPLAY 0.978723 (-1225 5400);
PAINT WHITE (-1225 5400);
DISPLAY INVISIBLE (-1225 5400);
FORCEADD Q_CAP..1
(-825 4475);
FORCEPROP 1 LAST LOCATION C2249
J 0
(-775 4575);
DISPLAY 0.489362 (-775 4575);
PAINT SKYBLUE (-775 4575);
FORCEPROP 2 LAST $SEC 1
J 0
(-775 4675);
DISPLAY 0.680851 (-775 4675);
PAINT MONO (-775 4675);
DISPLAY INVISIBLE (-775 4675);
FORCEPROP 2 LAST CDS_SEC 1
J 0
(-775 4675);
DISPLAY 1.021277 (-775 4675);
DISPLAY INVISIBLE (-775 4675);
FORCEPROP 1 LASTPIN (-825 4575) $PN 1
J 0
(-815 4555);
DISPLAY 0.489362 (-815 4555);
FORCEPROP 1 LASTPIN (-825 4375) $PN 2
J 0
(-815 4355);
DISPLAY 0.489362 (-815 4355);
FORCEPROP 1 LAST MATERIAL X6S
J 0
(-775 4375);
DISPLAY 0.489362 (-775 4375);
PAINT SKYBLUE (-775 4375);
FORCEPROP 1 LAST TOLERANCE 20%
J 0
(-775 4425);
DISPLAY 0.489362 (-775 4425);
PAINT SKYBLUE (-775 4425);
FORCEPROP 1 LAST VALUE 22UF
J 0
(-775 4525);
DISPLAY 0.489362 (-775 4525);
PAINT SKYBLUE (-775 4525);
FORCEPROP 1 LAST PART_NUMBER CH622KMEB02
J 0
(-775 4325);
DISPLAY 0.489362 (-775 4325);
PAINT SKYBLUE (-775 4325);
FORCEPROP 1 LAST VOLTAGE 4V
J 0
(-775 4475);
DISPLAY 0.489362 (-775 4475);
PAINT SKYBLUE (-775 4475);
FORCEPROP 1 LAST PACK_TYPE C0402
J 0
(-775 4275);
DISPLAY 0.489362 (-775 4275);
PAINT SKYBLUE (-775 4275);
FORCEPROP 2 LAST CDS_LIB pure_quanta
J 0
(-825 4475);
PAINT MONO (-825 4475);
DISPLAY INVISIBLE (-825 4475);
FORCEPROP 1 LAST PATH I105
J 0
(-775 4625);
DISPLAY 0.978723 (-775 4625);
PAINT WHITE (-775 4625);
DISPLAY INVISIBLE (-775 4625);
FORCEADD Q_CAP..1
(-425 4475);
FORCEPROP 1 LAST LOCATION C2254
J 0
(-375 4575);
DISPLAY 0.489362 (-375 4575);
PAINT SKYBLUE (-375 4575);
FORCEPROP 2 LAST $SEC 1
J 0
(-375 4675);
DISPLAY 0.680851 (-375 4675);
PAINT MONO (-375 4675);
DISPLAY INVISIBLE (-375 4675);
FORCEPROP 2 LAST CDS_SEC 1
J 0
(-375 4675);
DISPLAY 1.021277 (-375 4675);
DISPLAY INVISIBLE (-375 4675);
FORCEPROP 1 LASTPIN (-425 4575) $PN 1
J 0
(-415 4555);
DISPLAY 0.489362 (-415 4555);
FORCEPROP 1 LASTPIN (-425 4375) $PN 2
J 0
(-415 4355);
DISPLAY 0.489362 (-415 4355);
FORCEPROP 1 LAST MATERIAL X6S
J 0
(-375 4375);
DISPLAY 0.489362 (-375 4375);
PAINT SKYBLUE (-375 4375);
FORCEPROP 1 LAST TOLERANCE 20%
J 0
(-375 4425);
DISPLAY 0.489362 (-375 4425);
PAINT SKYBLUE (-375 4425);
FORCEPROP 1 LAST VALUE 22UF
J 0
(-375 4525);
DISPLAY 0.489362 (-375 4525);
PAINT SKYBLUE (-375 4525);
FORCEPROP 1 LAST PART_NUMBER CH622KMEB02
J 0
(-375 4325);
DISPLAY 0.489362 (-375 4325);
PAINT SKYBLUE (-375 4325);
FORCEPROP 1 LAST VOLTAGE 4V
J 0
(-375 4475);
DISPLAY 0.489362 (-375 4475);
PAINT SKYBLUE (-375 4475);
FORCEPROP 1 LAST PACK_TYPE C0402
J 0
(-375 4275);
DISPLAY 0.489362 (-375 4275);
PAINT SKYBLUE (-375 4275);
FORCEPROP 2 LAST CDS_LIB pure_quanta
J 0
(-425 4475);
PAINT MONO (-425 4475);
DISPLAY INVISIBLE (-425 4475);
FORCEPROP 1 LAST PATH I106
J 0
(-375 4625);
DISPLAY 0.978723 (-375 4625);
PAINT WHITE (-375 4625);
DISPLAY INVISIBLE (-375 4625);
FORCEADD UNIVERSAL_GND..1
(-425 4875);
FORCEPROP 3 LASTPIN (-425 4925) SIG_NAME GND\g
J 0
(-415 4935);
DISPLAY 0.659574 (-415 4935);
PAINT MONO (-415 4935);
DISPLAY INVISIBLE (-415 4935);
FORCEPROP 2 LAST CDS_LIB pure_quanta_power
J 0
(-425 4875);
PAINT MONO (-425 4875);
DISPLAY INVISIBLE (-425 4875);
FORCEPROP 1 LAST PATH I107
J 0
(-350 4875);
DISPLAY 0.872340 (-350 4875);
PAINT AQUA (-350 4875);
DISPLAY INVISIBLE (-350 4875);
FORCEPROP 1 LAST HDL_POWER GND
J 1
(-400 4800);
DISPLAY 0.872340 (-400 4800);
PAINT GREEN (-400 4800);
DISPLAY INVISIBLE (-400 4800);
FORCEADD Q_CAP..1
(-825 5250);
FORCEPROP 1 LAST LOCATION C2248
J 0
(-775 5350);
DISPLAY 0.489362 (-775 5350);
PAINT SKYBLUE (-775 5350);
FORCEPROP 2 LAST $SEC 1
J 0
(-775 5450);
DISPLAY 0.680851 (-775 5450);
PAINT MONO (-775 5450);
DISPLAY INVISIBLE (-775 5450);
FORCEPROP 2 LAST CDS_SEC 1
J 0
(-775 5450);
DISPLAY 1.021277 (-775 5450);
DISPLAY INVISIBLE (-775 5450);
FORCEPROP 1 LASTPIN (-825 5350) $PN 1
J 0
(-815 5330);
DISPLAY 0.489362 (-815 5330);
FORCEPROP 1 LASTPIN (-825 5150) $PN 2
J 0
(-815 5130);
DISPLAY 0.489362 (-815 5130);
FORCEPROP 1 LAST MATERIAL X6S
J 0
(-775 5150);
DISPLAY 0.489362 (-775 5150);
PAINT SKYBLUE (-775 5150);
FORCEPROP 1 LAST TOLERANCE 20%
J 0
(-775 5200);
DISPLAY 0.489362 (-775 5200);
PAINT SKYBLUE (-775 5200);
FORCEPROP 1 LAST VALUE 22UF
J 0
(-775 5300);
DISPLAY 0.489362 (-775 5300);
PAINT SKYBLUE (-775 5300);
FORCEPROP 1 LAST PART_NUMBER CH622KMEB02
J 0
(-775 5100);
DISPLAY 0.489362 (-775 5100);
PAINT SKYBLUE (-775 5100);
FORCEPROP 1 LAST VOLTAGE 4V
J 0
(-775 5250);
DISPLAY 0.489362 (-775 5250);
PAINT SKYBLUE (-775 5250);
FORCEPROP 1 LAST PACK_TYPE C0402
J 0
(-775 5050);
DISPLAY 0.489362 (-775 5050);
PAINT SKYBLUE (-775 5050);
FORCEPROP 2 LAST CDS_LIB pure_quanta
J 0
(-825 5250);
PAINT MONO (-825 5250);
DISPLAY INVISIBLE (-825 5250);
FORCEPROP 1 LAST PATH I108
J 0
(-775 5400);
DISPLAY 0.978723 (-775 5400);
PAINT WHITE (-775 5400);
DISPLAY INVISIBLE (-775 5400);
FORCEADD Q_CAP..1
(-425 5250);
FORCEPROP 1 LAST LOCATION C2253
J 0
(-375 5350);
DISPLAY 0.489362 (-375 5350);
PAINT SKYBLUE (-375 5350);
FORCEPROP 2 LAST $SEC 1
J 0
(-375 5450);
DISPLAY 0.680851 (-375 5450);
PAINT MONO (-375 5450);
DISPLAY INVISIBLE (-375 5450);
FORCEPROP 2 LAST CDS_SEC 1
J 0
(-375 5450);
DISPLAY 1.021277 (-375 5450);
DISPLAY INVISIBLE (-375 5450);
FORCEPROP 1 LASTPIN (-425 5350) $PN 1
J 0
(-415 5330);
DISPLAY 0.489362 (-415 5330);
FORCEPROP 1 LASTPIN (-425 5150) $PN 2
J 0
(-415 5130);
DISPLAY 0.489362 (-415 5130);
FORCEPROP 1 LAST MATERIAL X6S
J 0
(-375 5150);
DISPLAY 0.489362 (-375 5150);
PAINT SKYBLUE (-375 5150);
FORCEPROP 1 LAST TOLERANCE 20%
J 0
(-375 5200);
DISPLAY 0.489362 (-375 5200);
PAINT SKYBLUE (-375 5200);
FORCEPROP 1 LAST VALUE 22UF
J 0
(-375 5300);
DISPLAY 0.489362 (-375 5300);
PAINT SKYBLUE (-375 5300);
FORCEPROP 1 LAST PART_NUMBER CH622KMEB02
J 0
(-375 5100);
DISPLAY 0.489362 (-375 5100);
PAINT SKYBLUE (-375 5100);
FORCEPROP 1 LAST VOLTAGE 4V
J 0
(-375 5250);
DISPLAY 0.489362 (-375 5250);
PAINT SKYBLUE (-375 5250);
FORCEPROP 1 LAST PACK_TYPE C0402
J 0
(-375 5050);
DISPLAY 0.489362 (-375 5050);
PAINT SKYBLUE (-375 5050);
FORCEPROP 2 LAST CDS_LIB pure_quanta
J 0
(-425 5250);
PAINT MONO (-425 5250);
DISPLAY INVISIBLE (-425 5250);
FORCEPROP 1 LAST PATH I109
J 0
(-375 5400);
DISPLAY 0.978723 (-375 5400);
PAINT WHITE (-375 5400);
DISPLAY INVISIBLE (-375 5400);
FORCEADD UNIVERSAL_POWER..1
(-9000 4750);
FORCEPROP 3 LASTPIN (-9000 4700) SIG_NAME PVDDCR_CPU0_P0\g
J 0
(-8990 4710);
DISPLAY 0.659574 (-8990 4710);
PAINT MONO (-8990 4710);
DISPLAY INVISIBLE (-8990 4710);
FORCEPROP 1 LAST HDL_POWER PVDDCR_CPU0_P0
J 1
(-9000 4800);
DISPLAY 0.489362 (-9000 4800);
PAINT GREEN (-9000 4800);
FORCEPROP 2 LAST CDS_LIB pure_quanta_power
J 0
(-9000 4750);
DISPLAY INVISIBLE (-9000 4750);
FORCEPROP 1 LAST PATH I11
J 0
(-8950 4775);
DISPLAY 0.872340 (-8950 4775);
PAINT AQUA (-8950 4775);
DISPLAY INVISIBLE (-8950 4775);
FORCEADD Q_CAP..1
(-6300 5250);
FORCEPROP 1 LAST LOCATION C272
J 0
(-6250 5350);
DISPLAY 0.489362 (-6250 5350);
PAINT SKYBLUE (-6250 5350);
FORCEPROP 2 LAST $SEC 1
J 0
(-6250 5450);
DISPLAY 0.680851 (-6250 5450);
PAINT MONO (-6250 5450);
DISPLAY INVISIBLE (-6250 5450);
FORCEPROP 2 LAST CDS_SEC 1
J 0
(-6250 5450);
DISPLAY 1.021277 (-6250 5450);
DISPLAY INVISIBLE (-6250 5450);
FORCEPROP 1 LASTPIN (-6300 5350) $PN 1
J 0
(-6290 5330);
DISPLAY 0.489362 (-6290 5330);
FORCEPROP 1 LASTPIN (-6300 5150) $PN 2
J 0
(-6290 5130);
DISPLAY 0.489362 (-6290 5130);
FORCEPROP 1 LAST MATERIAL X6S
J 0
(-6250 5150);
DISPLAY 0.489362 (-6250 5150);
PAINT SKYBLUE (-6250 5150);
FORCEPROP 1 LAST TOLERANCE 20%
J 0
(-6250 5200);
DISPLAY 0.489362 (-6250 5200);
PAINT SKYBLUE (-6250 5200);
FORCEPROP 1 LAST VALUE 22UF
J 0
(-6250 5300);
DISPLAY 0.489362 (-6250 5300);
PAINT SKYBLUE (-6250 5300);
FORCEPROP 1 LAST PART_NUMBER CH622KMEB02
J 0
(-6250 5100);
DISPLAY 0.489362 (-6250 5100);
PAINT SKYBLUE (-6250 5100);
FORCEPROP 1 LAST VOLTAGE 4V
J 0
(-6250 5250);
DISPLAY 0.489362 (-6250 5250);
PAINT SKYBLUE (-6250 5250);
FORCEPROP 1 LAST PACK_TYPE C0402
J 0
(-6250 5050);
DISPLAY 0.489362 (-6250 5050);
PAINT SKYBLUE (-6250 5050);
FORCEPROP 2 LAST CDS_LIB pure_quanta
J 0
(-6300 5250);
PAINT MONO (-6300 5250);
DISPLAY INVISIBLE (-6300 5250);
FORCEPROP 1 LAST PATH I110
J 0
(-6250 5400);
DISPLAY 0.978723 (-6250 5400);
PAINT WHITE (-6250 5400);
DISPLAY INVISIBLE (-6250 5400);
FORCEADD Q_CAP..1
(-8550 4475);
FORCEPROP 1 LAST LOCATION C252
J 0
(-8500 4575);
DISPLAY 0.489362 (-8500 4575);
PAINT SKYBLUE (-8500 4575);
FORCEPROP 2 LAST $SEC 1
J 0
(-8500 4675);
DISPLAY 0.680851 (-8500 4675);
PAINT MONO (-8500 4675);
DISPLAY INVISIBLE (-8500 4675);
FORCEPROP 2 LAST CDS_SEC 1
J 0
(-8500 4675);
DISPLAY 1.021277 (-8500 4675);
DISPLAY INVISIBLE (-8500 4675);
FORCEPROP 1 LASTPIN (-8550 4575) $PN 1
J 0
(-8540 4555);
DISPLAY 0.489362 (-8540 4555);
FORCEPROP 1 LASTPIN (-8550 4375) $PN 2
J 0
(-8540 4355);
DISPLAY 0.489362 (-8540 4355);
FORCEPROP 1 LAST MATERIAL X6S
J 0
(-8500 4375);
DISPLAY 0.489362 (-8500 4375);
PAINT SKYBLUE (-8500 4375);
FORCEPROP 1 LAST TOLERANCE 20%
J 0
(-8500 4425);
DISPLAY 0.489362 (-8500 4425);
PAINT SKYBLUE (-8500 4425);
FORCEPROP 1 LAST VALUE 22UF
J 0
(-8500 4525);
DISPLAY 0.489362 (-8500 4525);
PAINT SKYBLUE (-8500 4525);
FORCEPROP 1 LAST PART_NUMBER CH622KMEB02
J 0
(-8500 4325);
DISPLAY 0.489362 (-8500 4325);
PAINT SKYBLUE (-8500 4325);
FORCEPROP 1 LAST VOLTAGE 4V
J 0
(-8500 4475);
DISPLAY 0.489362 (-8500 4475);
PAINT SKYBLUE (-8500 4475);
FORCEPROP 1 LAST PACK_TYPE C0402
J 0
(-8500 4275);
DISPLAY 0.489362 (-8500 4275);
PAINT SKYBLUE (-8500 4275);
FORCEPROP 2 LAST CDS_LIB pure_quanta
J 0
(-8550 4475);
PAINT MONO (-8550 4475);
DISPLAY INVISIBLE (-8550 4475);
FORCEPROP 1 LAST PATH I12
J 0
(-8500 4625);
DISPLAY 0.978723 (-8500 4625);
PAINT WHITE (-8500 4625);
DISPLAY INVISIBLE (-8500 4625);
FORCEADD UNIVERSAL_POWER..1
(-9000 5525);
FORCEPROP 3 LASTPIN (-9000 5475) SIG_NAME PVDDCR_CPU0_P0\g
J 0
(-8990 5485);
DISPLAY 0.659574 (-8990 5485);
PAINT MONO (-8990 5485);
DISPLAY INVISIBLE (-8990 5485);
FORCEPROP 1 LAST HDL_POWER PVDDCR_CPU0_P0
J 1
(-9000 5575);
DISPLAY 0.489362 (-9000 5575);
PAINT GREEN (-9000 5575);
FORCEPROP 2 LAST CDS_LIB pure_quanta_power
J 0
(-9000 5525);
DISPLAY INVISIBLE (-9000 5525);
FORCEPROP 1 LAST PATH I13
J 0
(-8950 5550);
DISPLAY 0.872340 (-8950 5550);
PAINT AQUA (-8950 5550);
DISPLAY INVISIBLE (-8950 5550);
FORCEADD Q_CAP..1
(-9000 5250);
FORCEPROP 1 LAST LOCATION C245
J 0
(-8950 5350);
DISPLAY 0.489362 (-8950 5350);
PAINT SKYBLUE (-8950 5350);
FORCEPROP 2 LAST $SEC 1
J 0
(-8950 5450);
DISPLAY 0.680851 (-8950 5450);
PAINT MONO (-8950 5450);
DISPLAY INVISIBLE (-8950 5450);
FORCEPROP 2 LAST CDS_SEC 1
J 0
(-8950 5450);
DISPLAY 1.021277 (-8950 5450);
DISPLAY INVISIBLE (-8950 5450);
FORCEPROP 1 LASTPIN (-9000 5350) $PN 1
J 0
(-8990 5330);
DISPLAY 0.489362 (-8990 5330);
FORCEPROP 1 LASTPIN (-9000 5150) $PN 2
J 0
(-8990 5130);
DISPLAY 0.489362 (-8990 5130);
FORCEPROP 1 LAST MATERIAL X6S
J 0
(-8950 5150);
DISPLAY 0.489362 (-8950 5150);
PAINT SKYBLUE (-8950 5150);
FORCEPROP 1 LAST TOLERANCE 20%
J 0
(-8950 5200);
DISPLAY 0.489362 (-8950 5200);
PAINT SKYBLUE (-8950 5200);
FORCEPROP 1 LAST VALUE 22UF
J 0
(-8950 5300);
DISPLAY 0.489362 (-8950 5300);
PAINT SKYBLUE (-8950 5300);
FORCEPROP 1 LAST PART_NUMBER CH622KMEB02
J 0
(-8950 5100);
DISPLAY 0.489362 (-8950 5100);
PAINT SKYBLUE (-8950 5100);
FORCEPROP 1 LAST VOLTAGE 4V
J 0
(-8950 5250);
DISPLAY 0.489362 (-8950 5250);
PAINT SKYBLUE (-8950 5250);
FORCEPROP 1 LAST PACK_TYPE C0402
J 0
(-8950 5050);
DISPLAY 0.489362 (-8950 5050);
PAINT SKYBLUE (-8950 5050);
FORCEPROP 2 LAST CDS_LIB pure_quanta
J 0
(-9000 5250);
PAINT MONO (-9000 5250);
DISPLAY INVISIBLE (-9000 5250);
FORCEPROP 1 LAST PATH I14
J 0
(-8950 5400);
DISPLAY 0.978723 (-8950 5400);
PAINT WHITE (-8950 5400);
DISPLAY INVISIBLE (-8950 5400);
FORCEADD Q_CAP..1
(-8550 5250);
FORCEPROP 1 LAST LOCATION C251
J 0
(-8500 5350);
DISPLAY 0.489362 (-8500 5350);
PAINT SKYBLUE (-8500 5350);
FORCEPROP 2 LAST $SEC 1
J 0
(-8500 5450);
DISPLAY 0.680851 (-8500 5450);
PAINT MONO (-8500 5450);
DISPLAY INVISIBLE (-8500 5450);
FORCEPROP 2 LAST CDS_SEC 1
J 0
(-8500 5450);
DISPLAY 1.021277 (-8500 5450);
DISPLAY INVISIBLE (-8500 5450);
FORCEPROP 1 LASTPIN (-8550 5350) $PN 1
J 0
(-8540 5330);
DISPLAY 0.489362 (-8540 5330);
FORCEPROP 1 LASTPIN (-8550 5150) $PN 2
J 0
(-8540 5130);
DISPLAY 0.489362 (-8540 5130);
FORCEPROP 1 LAST MATERIAL X6S
J 0
(-8500 5150);
DISPLAY 0.489362 (-8500 5150);
PAINT SKYBLUE (-8500 5150);
FORCEPROP 1 LAST TOLERANCE 20%
J 0
(-8500 5200);
DISPLAY 0.489362 (-8500 5200);
PAINT SKYBLUE (-8500 5200);
FORCEPROP 1 LAST VALUE 22UF
J 0
(-8500 5300);
DISPLAY 0.489362 (-8500 5300);
PAINT SKYBLUE (-8500 5300);
FORCEPROP 1 LAST PART_NUMBER CH622KMEB02
J 0
(-8500 5100);
DISPLAY 0.489362 (-8500 5100);
PAINT SKYBLUE (-8500 5100);
FORCEPROP 1 LAST VOLTAGE 4V
J 0
(-8500 5250);
DISPLAY 0.489362 (-8500 5250);
PAINT SKYBLUE (-8500 5250);
FORCEPROP 1 LAST PACK_TYPE C0402
J 0
(-8500 5050);
DISPLAY 0.489362 (-8500 5050);
PAINT SKYBLUE (-8500 5050);
FORCEPROP 2 LAST CDS_LIB pure_quanta
J 0
(-8550 5250);
PAINT MONO (-8550 5250);
DISPLAY INVISIBLE (-8550 5250);
FORCEPROP 1 LAST PATH I15
J 0
(-8500 5400);
DISPLAY 0.978723 (-8500 5400);
PAINT WHITE (-8500 5400);
DISPLAY INVISIBLE (-8500 5400);
FORCEADD Q_CAP..1
(-8100 2075);
FORCEPROP 1 LAST LOCATION C2175
J 0
(-8050 2175);
DISPLAY 0.489362 (-8050 2175);
PAINT SKYBLUE (-8050 2175);
FORCEPROP 2 LAST $SEC 1
J 0
(-8050 2275);
DISPLAY 0.680851 (-8050 2275);
PAINT MONO (-8050 2275);
DISPLAY INVISIBLE (-8050 2275);
FORCEPROP 2 LAST CDS_SEC 1
J 0
(-8050 2275);
DISPLAY 1.021277 (-8050 2275);
DISPLAY INVISIBLE (-8050 2275);
FORCEPROP 1 LASTPIN (-8100 2175) $PN 1
J 0
(-8090 2155);
DISPLAY 0.489362 (-8090 2155);
FORCEPROP 1 LASTPIN (-8100 1975) $PN 2
J 0
(-8090 1955);
DISPLAY 0.489362 (-8090 1955);
FORCEPROP 1 LAST MATERIAL X6S
J 0
(-8050 1975);
DISPLAY 0.489362 (-8050 1975);
PAINT SKYBLUE (-8050 1975);
FORCEPROP 1 LAST TOLERANCE 20%
J 0
(-8050 2025);
DISPLAY 0.489362 (-8050 2025);
PAINT SKYBLUE (-8050 2025);
FORCEPROP 1 LAST VALUE 22UF
J 0
(-8050 2125);
DISPLAY 0.489362 (-8050 2125);
PAINT SKYBLUE (-8050 2125);
FORCEPROP 1 LAST PART_NUMBER CH622KMEB02
J 0
(-8050 1925);
DISPLAY 0.489362 (-8050 1925);
PAINT SKYBLUE (-8050 1925);
FORCEPROP 1 LAST VOLTAGE 4V
J 0
(-8050 2075);
DISPLAY 0.489362 (-8050 2075);
PAINT SKYBLUE (-8050 2075);
FORCEPROP 1 LAST PACK_TYPE C0402
J 0
(-8050 1875);
DISPLAY 0.489362 (-8050 1875);
PAINT SKYBLUE (-8050 1875);
FORCEPROP 2 LAST CDS_LIB pure_quanta
J 0
(-8100 2075);
PAINT MONO (-8100 2075);
DISPLAY INVISIBLE (-8100 2075);
FORCEPROP 1 LAST PATH I16
J 0
(-8050 2225);
DISPLAY 0.978723 (-8050 2225);
PAINT WHITE (-8050 2225);
DISPLAY INVISIBLE (-8050 2225);
FORCEADD Q_CAP..1
(-7650 2075);
FORCEPROP 1 LAST LOCATION C2179
J 0
(-7600 2175);
DISPLAY 0.489362 (-7600 2175);
PAINT SKYBLUE (-7600 2175);
FORCEPROP 2 LAST $SEC 1
J 0
(-7600 2275);
DISPLAY 0.680851 (-7600 2275);
PAINT MONO (-7600 2275);
DISPLAY INVISIBLE (-7600 2275);
FORCEPROP 2 LAST CDS_SEC 1
J 0
(-7600 2275);
DISPLAY 1.021277 (-7600 2275);
DISPLAY INVISIBLE (-7600 2275);
FORCEPROP 1 LASTPIN (-7650 2175) $PN 1
J 0
(-7640 2155);
DISPLAY 0.489362 (-7640 2155);
FORCEPROP 1 LASTPIN (-7650 1975) $PN 2
J 0
(-7640 1955);
DISPLAY 0.489362 (-7640 1955);
FORCEPROP 1 LAST MATERIAL X6S
J 0
(-7600 1975);
DISPLAY 0.489362 (-7600 1975);
PAINT SKYBLUE (-7600 1975);
FORCEPROP 1 LAST TOLERANCE 20%
J 0
(-7600 2025);
DISPLAY 0.489362 (-7600 2025);
PAINT SKYBLUE (-7600 2025);
FORCEPROP 1 LAST VALUE 22UF
J 0
(-7600 2125);
DISPLAY 0.489362 (-7600 2125);
PAINT SKYBLUE (-7600 2125);
FORCEPROP 1 LAST PART_NUMBER CH622KMEB02
J 0
(-7600 1925);
DISPLAY 0.489362 (-7600 1925);
PAINT SKYBLUE (-7600 1925);
FORCEPROP 1 LAST VOLTAGE 4V
J 0
(-7600 2075);
DISPLAY 0.489362 (-7600 2075);
PAINT SKYBLUE (-7600 2075);
FORCEPROP 1 LAST PACK_TYPE C0402
J 0
(-7600 1875);
DISPLAY 0.489362 (-7600 1875);
PAINT SKYBLUE (-7600 1875);
FORCEPROP 2 LAST CDS_LIB pure_quanta
J 0
(-7650 2075);
PAINT MONO (-7650 2075);
DISPLAY INVISIBLE (-7650 2075);
FORCEPROP 1 LAST PATH I17
J 0
(-7600 2225);
DISPLAY 0.978723 (-7600 2225);
PAINT WHITE (-7600 2225);
DISPLAY INVISIBLE (-7600 2225);
FORCEADD UNIVERSAL_GND..1
(-7200 1675);
FORCEPROP 3 LASTPIN (-7200 1725) SIG_NAME GND\g
J 0
(-7190 1735);
DISPLAY 0.659574 (-7190 1735);
PAINT MONO (-7190 1735);
DISPLAY INVISIBLE (-7190 1735);
FORCEPROP 2 LAST CDS_LIB pure_quanta_power
J 0
(-7200 1675);
PAINT MONO (-7200 1675);
DISPLAY INVISIBLE (-7200 1675);
FORCEPROP 1 LAST PATH I18
J 0
(-7125 1675);
DISPLAY 0.872340 (-7125 1675);
PAINT AQUA (-7125 1675);
DISPLAY INVISIBLE (-7125 1675);
FORCEPROP 1 LAST HDL_POWER GND
J 1
(-7175 1600);
DISPLAY 0.872340 (-7175 1600);
PAINT GREEN (-7175 1600);
DISPLAY INVISIBLE (-7175 1600);
FORCEADD Q_CAP..1
(-7200 2075);
FORCEPROP 1 LAST LOCATION C2183
J 0
(-7150 2175);
DISPLAY 0.489362 (-7150 2175);
PAINT SKYBLUE (-7150 2175);
FORCEPROP 2 LAST $SEC 1
J 0
(-7150 2275);
DISPLAY 0.680851 (-7150 2275);
PAINT MONO (-7150 2275);
DISPLAY INVISIBLE (-7150 2275);
FORCEPROP 2 LAST CDS_SEC 1
J 0
(-7150 2275);
DISPLAY 1.021277 (-7150 2275);
DISPLAY INVISIBLE (-7150 2275);
FORCEPROP 1 LASTPIN (-7200 2175) $PN 1
J 0
(-7190 2155);
DISPLAY 0.489362 (-7190 2155);
FORCEPROP 1 LASTPIN (-7200 1975) $PN 2
J 0
(-7190 1955);
DISPLAY 0.489362 (-7190 1955);
FORCEPROP 1 LAST MATERIAL X6S
J 0
(-7150 1975);
DISPLAY 0.489362 (-7150 1975);
PAINT SKYBLUE (-7150 1975);
FORCEPROP 1 LAST TOLERANCE 20%
J 0
(-7150 2025);
DISPLAY 0.489362 (-7150 2025);
PAINT SKYBLUE (-7150 2025);
FORCEPROP 1 LAST VALUE 22UF
J 0
(-7150 2125);
DISPLAY 0.489362 (-7150 2125);
PAINT SKYBLUE (-7150 2125);
FORCEPROP 1 LAST PART_NUMBER CH622KMEB02
J 0
(-7150 1925);
DISPLAY 0.489362 (-7150 1925);
PAINT SKYBLUE (-7150 1925);
FORCEPROP 1 LAST VOLTAGE 4V
J 0
(-7150 2075);
DISPLAY 0.489362 (-7150 2075);
PAINT SKYBLUE (-7150 2075);
FORCEPROP 1 LAST PACK_TYPE C0402
J 0
(-7150 1875);
DISPLAY 0.489362 (-7150 1875);
PAINT SKYBLUE (-7150 1875);
FORCEPROP 2 LAST CDS_LIB pure_quanta
J 0
(-7200 2075);
PAINT MONO (-7200 2075);
DISPLAY INVISIBLE (-7200 2075);
FORCEPROP 1 LAST PATH I19
J 0
(-7150 2225);
DISPLAY 0.978723 (-7150 2225);
PAINT WHITE (-7150 2225);
DISPLAY INVISIBLE (-7150 2225);
FORCEADD Q_CAP..1
(-8550 2075);
FORCEPROP 1 LAST LOCATION C2171
J 0
(-8500 2175);
DISPLAY 0.489362 (-8500 2175);
PAINT SKYBLUE (-8500 2175);
FORCEPROP 2 LAST $SEC 1
J 0
(-8500 2275);
DISPLAY 0.680851 (-8500 2275);
PAINT MONO (-8500 2275);
DISPLAY INVISIBLE (-8500 2275);
FORCEPROP 2 LAST CDS_SEC 1
J 0
(-8500 2275);
DISPLAY 1.021277 (-8500 2275);
DISPLAY INVISIBLE (-8500 2275);
FORCEPROP 1 LASTPIN (-8550 2175) $PN 1
J 0
(-8540 2155);
DISPLAY 0.489362 (-8540 2155);
FORCEPROP 1 LASTPIN (-8550 1975) $PN 2
J 0
(-8540 1955);
DISPLAY 0.489362 (-8540 1955);
FORCEPROP 1 LAST MATERIAL X6S
J 0
(-8500 1975);
DISPLAY 0.489362 (-8500 1975);
PAINT SKYBLUE (-8500 1975);
FORCEPROP 1 LAST TOLERANCE 20%
J 0
(-8500 2025);
DISPLAY 0.489362 (-8500 2025);
PAINT SKYBLUE (-8500 2025);
FORCEPROP 1 LAST VALUE 22UF
J 0
(-8500 2125);
DISPLAY 0.489362 (-8500 2125);
PAINT SKYBLUE (-8500 2125);
FORCEPROP 1 LAST PART_NUMBER CH622KMEB02
J 0
(-8500 1925);
DISPLAY 0.489362 (-8500 1925);
PAINT SKYBLUE (-8500 1925);
FORCEPROP 1 LAST VOLTAGE 4V
J 0
(-8500 2075);
DISPLAY 0.489362 (-8500 2075);
PAINT SKYBLUE (-8500 2075);
FORCEPROP 1 LAST PACK_TYPE C0402
J 0
(-8500 1875);
DISPLAY 0.489362 (-8500 1875);
PAINT SKYBLUE (-8500 1875);
FORCEPROP 2 LAST CDS_LIB pure_quanta
J 0
(-8550 2075);
PAINT MONO (-8550 2075);
DISPLAY INVISIBLE (-8550 2075);
FORCEPROP 1 LAST PATH I2
J 0
(-8500 2225);
DISPLAY 0.978723 (-8500 2225);
PAINT WHITE (-8500 2225);
DISPLAY INVISIBLE (-8500 2225);
FORCEADD Q_CAP..1
(-8100 2875);
FORCEPROP 1 LAST LOCATION C2174
J 0
(-8050 2975);
DISPLAY 0.489362 (-8050 2975);
PAINT SKYBLUE (-8050 2975);
FORCEPROP 2 LAST $SEC 1
J 0
(-8050 3075);
DISPLAY 0.680851 (-8050 3075);
PAINT MONO (-8050 3075);
DISPLAY INVISIBLE (-8050 3075);
FORCEPROP 2 LAST CDS_SEC 1
J 0
(-8050 3075);
DISPLAY 1.021277 (-8050 3075);
DISPLAY INVISIBLE (-8050 3075);
FORCEPROP 1 LASTPIN (-8100 2975) $PN 1
J 0
(-8090 2955);
DISPLAY 0.489362 (-8090 2955);
FORCEPROP 1 LASTPIN (-8100 2775) $PN 2
J 0
(-8090 2755);
DISPLAY 0.489362 (-8090 2755);
FORCEPROP 1 LAST MATERIAL X6S
J 0
(-8050 2775);
DISPLAY 0.489362 (-8050 2775);
PAINT SKYBLUE (-8050 2775);
FORCEPROP 1 LAST TOLERANCE 20%
J 0
(-8050 2825);
DISPLAY 0.489362 (-8050 2825);
PAINT SKYBLUE (-8050 2825);
FORCEPROP 1 LAST VALUE 22UF
J 0
(-8050 2925);
DISPLAY 0.489362 (-8050 2925);
PAINT SKYBLUE (-8050 2925);
FORCEPROP 1 LAST PART_NUMBER CH622KMEB02
J 0
(-8050 2725);
DISPLAY 0.489362 (-8050 2725);
PAINT SKYBLUE (-8050 2725);
FORCEPROP 1 LAST VOLTAGE 4V
J 0
(-8050 2875);
DISPLAY 0.489362 (-8050 2875);
PAINT SKYBLUE (-8050 2875);
FORCEPROP 1 LAST PACK_TYPE C0402
J 0
(-8050 2675);
DISPLAY 0.489362 (-8050 2675);
PAINT SKYBLUE (-8050 2675);
FORCEPROP 2 LAST CDS_LIB pure_quanta
J 0
(-8100 2875);
PAINT MONO (-8100 2875);
DISPLAY INVISIBLE (-8100 2875);
FORCEPROP 1 LAST PATH I20
J 0
(-8050 3025);
DISPLAY 0.978723 (-8050 3025);
PAINT WHITE (-8050 3025);
DISPLAY INVISIBLE (-8050 3025);
FORCEADD Q_CAP..1
(-7650 2875);
FORCEPROP 1 LAST LOCATION C2178
J 0
(-7600 2975);
DISPLAY 0.489362 (-7600 2975);
PAINT SKYBLUE (-7600 2975);
FORCEPROP 2 LAST $SEC 1
J 0
(-7600 3075);
DISPLAY 0.680851 (-7600 3075);
PAINT MONO (-7600 3075);
DISPLAY INVISIBLE (-7600 3075);
FORCEPROP 2 LAST CDS_SEC 1
J 0
(-7600 3075);
DISPLAY 1.021277 (-7600 3075);
DISPLAY INVISIBLE (-7600 3075);
FORCEPROP 1 LASTPIN (-7650 2975) $PN 1
J 0
(-7640 2955);
DISPLAY 0.489362 (-7640 2955);
FORCEPROP 1 LASTPIN (-7650 2775) $PN 2
J 0
(-7640 2755);
DISPLAY 0.489362 (-7640 2755);
FORCEPROP 1 LAST MATERIAL X6S
J 0
(-7600 2775);
DISPLAY 0.489362 (-7600 2775);
PAINT SKYBLUE (-7600 2775);
FORCEPROP 1 LAST TOLERANCE 20%
J 0
(-7600 2825);
DISPLAY 0.489362 (-7600 2825);
PAINT SKYBLUE (-7600 2825);
FORCEPROP 1 LAST VALUE 22UF
J 0
(-7600 2925);
DISPLAY 0.489362 (-7600 2925);
PAINT SKYBLUE (-7600 2925);
FORCEPROP 1 LAST PART_NUMBER CH622KMEB02
J 0
(-7600 2725);
DISPLAY 0.489362 (-7600 2725);
PAINT SKYBLUE (-7600 2725);
FORCEPROP 1 LAST VOLTAGE 4V
J 0
(-7600 2875);
DISPLAY 0.489362 (-7600 2875);
PAINT SKYBLUE (-7600 2875);
FORCEPROP 1 LAST PACK_TYPE C0402
J 0
(-7600 2675);
DISPLAY 0.489362 (-7600 2675);
PAINT SKYBLUE (-7600 2675);
FORCEPROP 2 LAST CDS_LIB pure_quanta
J 0
(-7650 2875);
PAINT MONO (-7650 2875);
DISPLAY INVISIBLE (-7650 2875);
FORCEPROP 1 LAST PATH I21
J 0
(-7600 3025);
DISPLAY 0.978723 (-7600 3025);
PAINT WHITE (-7600 3025);
DISPLAY INVISIBLE (-7600 3025);
FORCEADD Q_CAP..1
(-8100 3675);
FORCEPROP 1 LAST LOCATION C2173
J 0
(-8050 3775);
DISPLAY 0.489362 (-8050 3775);
PAINT SKYBLUE (-8050 3775);
FORCEPROP 2 LAST $SEC 1
J 0
(-8050 3875);
DISPLAY 0.680851 (-8050 3875);
PAINT MONO (-8050 3875);
DISPLAY INVISIBLE (-8050 3875);
FORCEPROP 2 LAST CDS_SEC 1
J 0
(-8050 3875);
DISPLAY 1.021277 (-8050 3875);
DISPLAY INVISIBLE (-8050 3875);
FORCEPROP 1 LASTPIN (-8100 3775) $PN 1
J 0
(-8090 3755);
DISPLAY 0.489362 (-8090 3755);
FORCEPROP 1 LASTPIN (-8100 3575) $PN 2
J 0
(-8090 3555);
DISPLAY 0.489362 (-8090 3555);
FORCEPROP 1 LAST MATERIAL X6S
J 0
(-8050 3575);
DISPLAY 0.489362 (-8050 3575);
PAINT SKYBLUE (-8050 3575);
FORCEPROP 1 LAST TOLERANCE 20%
J 0
(-8050 3625);
DISPLAY 0.489362 (-8050 3625);
PAINT SKYBLUE (-8050 3625);
FORCEPROP 1 LAST VALUE 22UF
J 0
(-8050 3725);
DISPLAY 0.489362 (-8050 3725);
PAINT SKYBLUE (-8050 3725);
FORCEPROP 1 LAST PART_NUMBER CH622KMEB02
J 0
(-8050 3525);
DISPLAY 0.489362 (-8050 3525);
PAINT SKYBLUE (-8050 3525);
FORCEPROP 1 LAST VOLTAGE 4V
J 0
(-8050 3675);
DISPLAY 0.489362 (-8050 3675);
PAINT SKYBLUE (-8050 3675);
FORCEPROP 1 LAST PACK_TYPE C0402
J 0
(-8050 3475);
DISPLAY 0.489362 (-8050 3475);
PAINT SKYBLUE (-8050 3475);
FORCEPROP 2 LAST CDS_LIB pure_quanta
J 0
(-8100 3675);
PAINT MONO (-8100 3675);
DISPLAY INVISIBLE (-8100 3675);
FORCEPROP 1 LAST PATH I22
J 0
(-8050 3825);
DISPLAY 0.978723 (-8050 3825);
PAINT WHITE (-8050 3825);
DISPLAY INVISIBLE (-8050 3825);
FORCEADD Q_CAP..1
(-7650 3675);
FORCEPROP 1 LAST LOCATION C2177
J 0
(-7600 3775);
DISPLAY 0.489362 (-7600 3775);
PAINT SKYBLUE (-7600 3775);
FORCEPROP 2 LAST $SEC 1
J 0
(-7600 3875);
DISPLAY 0.680851 (-7600 3875);
PAINT MONO (-7600 3875);
DISPLAY INVISIBLE (-7600 3875);
FORCEPROP 2 LAST CDS_SEC 1
J 0
(-7600 3875);
DISPLAY 1.021277 (-7600 3875);
DISPLAY INVISIBLE (-7600 3875);
FORCEPROP 1 LASTPIN (-7650 3775) $PN 1
J 0
(-7640 3755);
DISPLAY 0.489362 (-7640 3755);
FORCEPROP 1 LASTPIN (-7650 3575) $PN 2
J 0
(-7640 3555);
DISPLAY 0.489362 (-7640 3555);
FORCEPROP 1 LAST MATERIAL X6S
J 0
(-7600 3575);
DISPLAY 0.489362 (-7600 3575);
PAINT SKYBLUE (-7600 3575);
FORCEPROP 1 LAST TOLERANCE 20%
J 0
(-7600 3625);
DISPLAY 0.489362 (-7600 3625);
PAINT SKYBLUE (-7600 3625);
FORCEPROP 1 LAST VALUE 22UF
J 0
(-7600 3725);
DISPLAY 0.489362 (-7600 3725);
PAINT SKYBLUE (-7600 3725);
FORCEPROP 1 LAST PART_NUMBER CH622KMEB02
J 0
(-7600 3525);
DISPLAY 0.489362 (-7600 3525);
PAINT SKYBLUE (-7600 3525);
FORCEPROP 1 LAST VOLTAGE 4V
J 0
(-7600 3675);
DISPLAY 0.489362 (-7600 3675);
PAINT SKYBLUE (-7600 3675);
FORCEPROP 1 LAST PACK_TYPE C0402
J 0
(-7600 3475);
DISPLAY 0.489362 (-7600 3475);
PAINT SKYBLUE (-7600 3475);
FORCEPROP 2 LAST CDS_LIB pure_quanta
J 0
(-7650 3675);
PAINT MONO (-7650 3675);
DISPLAY INVISIBLE (-7650 3675);
FORCEPROP 1 LAST PATH I23
J 0
(-7600 3825);
DISPLAY 0.978723 (-7600 3825);
PAINT WHITE (-7600 3825);
DISPLAY INVISIBLE (-7600 3825);
FORCEADD Q_CAP..1
(-7200 2875);
FORCEPROP 1 LAST LOCATION C2182
J 0
(-7150 2975);
DISPLAY 0.489362 (-7150 2975);
PAINT SKYBLUE (-7150 2975);
FORCEPROP 2 LAST $SEC 1
J 0
(-7150 3075);
DISPLAY 0.680851 (-7150 3075);
PAINT MONO (-7150 3075);
DISPLAY INVISIBLE (-7150 3075);
FORCEPROP 2 LAST CDS_SEC 1
J 0
(-7150 3075);
DISPLAY 1.021277 (-7150 3075);
DISPLAY INVISIBLE (-7150 3075);
FORCEPROP 1 LASTPIN (-7200 2975) $PN 1
J 0
(-7190 2955);
DISPLAY 0.489362 (-7190 2955);
FORCEPROP 1 LASTPIN (-7200 2775) $PN 2
J 0
(-7190 2755);
DISPLAY 0.489362 (-7190 2755);
FORCEPROP 1 LAST MATERIAL X6S
J 0
(-7150 2775);
DISPLAY 0.489362 (-7150 2775);
PAINT SKYBLUE (-7150 2775);
FORCEPROP 1 LAST TOLERANCE 20%
J 0
(-7150 2825);
DISPLAY 0.489362 (-7150 2825);
PAINT SKYBLUE (-7150 2825);
FORCEPROP 1 LAST VALUE 22UF
J 0
(-7150 2925);
DISPLAY 0.489362 (-7150 2925);
PAINT SKYBLUE (-7150 2925);
FORCEPROP 1 LAST PART_NUMBER CH622KMEB02
J 0
(-7150 2725);
DISPLAY 0.489362 (-7150 2725);
PAINT SKYBLUE (-7150 2725);
FORCEPROP 1 LAST VOLTAGE 4V
J 0
(-7150 2875);
DISPLAY 0.489362 (-7150 2875);
PAINT SKYBLUE (-7150 2875);
FORCEPROP 1 LAST PACK_TYPE C0402
J 0
(-7150 2675);
DISPLAY 0.489362 (-7150 2675);
PAINT SKYBLUE (-7150 2675);
FORCEPROP 2 LAST CDS_LIB pure_quanta
J 0
(-7200 2875);
PAINT MONO (-7200 2875);
DISPLAY INVISIBLE (-7200 2875);
FORCEPROP 1 LAST PATH I24
J 0
(-7150 3025);
DISPLAY 0.978723 (-7150 3025);
PAINT WHITE (-7150 3025);
DISPLAY INVISIBLE (-7150 3025);
FORCEADD Q_CAP..1
(-7200 3675);
FORCEPROP 1 LAST LOCATION C2181
J 0
(-7150 3775);
DISPLAY 0.489362 (-7150 3775);
PAINT SKYBLUE (-7150 3775);
FORCEPROP 2 LAST $SEC 1
J 0
(-7150 3875);
DISPLAY 0.680851 (-7150 3875);
PAINT MONO (-7150 3875);
DISPLAY INVISIBLE (-7150 3875);
FORCEPROP 2 LAST CDS_SEC 1
J 0
(-7150 3875);
DISPLAY 1.021277 (-7150 3875);
DISPLAY INVISIBLE (-7150 3875);
FORCEPROP 1 LASTPIN (-7200 3775) $PN 1
J 0
(-7190 3755);
DISPLAY 0.489362 (-7190 3755);
FORCEPROP 1 LASTPIN (-7200 3575) $PN 2
J 0
(-7190 3555);
DISPLAY 0.489362 (-7190 3555);
FORCEPROP 1 LAST MATERIAL X6S
J 0
(-7150 3575);
DISPLAY 0.489362 (-7150 3575);
PAINT SKYBLUE (-7150 3575);
FORCEPROP 1 LAST TOLERANCE 20%
J 0
(-7150 3625);
DISPLAY 0.489362 (-7150 3625);
PAINT SKYBLUE (-7150 3625);
FORCEPROP 1 LAST VALUE 22UF
J 0
(-7150 3725);
DISPLAY 0.489362 (-7150 3725);
PAINT SKYBLUE (-7150 3725);
FORCEPROP 1 LAST PART_NUMBER CH622KMEB02
J 0
(-7150 3525);
DISPLAY 0.489362 (-7150 3525);
PAINT SKYBLUE (-7150 3525);
FORCEPROP 1 LAST VOLTAGE 4V
J 0
(-7150 3675);
DISPLAY 0.489362 (-7150 3675);
PAINT SKYBLUE (-7150 3675);
FORCEPROP 1 LAST PACK_TYPE C0402
J 0
(-7150 3475);
DISPLAY 0.489362 (-7150 3475);
PAINT SKYBLUE (-7150 3475);
FORCEPROP 2 LAST CDS_LIB pure_quanta
J 0
(-7200 3675);
PAINT MONO (-7200 3675);
DISPLAY INVISIBLE (-7200 3675);
FORCEPROP 1 LAST PATH I25
J 0
(-7150 3825);
DISPLAY 0.978723 (-7150 3825);
PAINT WHITE (-7150 3825);
DISPLAY INVISIBLE (-7150 3825);
FORCEADD Q_CAP..1
(-6750 2875);
FORCEPROP 1 LAST LOCATION C2186
J 0
(-6700 2975);
DISPLAY 0.489362 (-6700 2975);
PAINT SKYBLUE (-6700 2975);
FORCEPROP 2 LAST $SEC 1
J 0
(-6700 3075);
DISPLAY 0.680851 (-6700 3075);
PAINT MONO (-6700 3075);
DISPLAY INVISIBLE (-6700 3075);
FORCEPROP 2 LAST CDS_SEC 1
J 0
(-6700 3075);
DISPLAY 1.021277 (-6700 3075);
DISPLAY INVISIBLE (-6700 3075);
FORCEPROP 1 LASTPIN (-6750 2975) $PN 1
J 0
(-6740 2955);
DISPLAY 0.489362 (-6740 2955);
FORCEPROP 1 LASTPIN (-6750 2775) $PN 2
J 0
(-6740 2755);
DISPLAY 0.489362 (-6740 2755);
FORCEPROP 1 LAST MATERIAL X6S
J 0
(-6700 2775);
DISPLAY 0.489362 (-6700 2775);
PAINT SKYBLUE (-6700 2775);
FORCEPROP 1 LAST TOLERANCE 20%
J 0
(-6700 2825);
DISPLAY 0.489362 (-6700 2825);
PAINT SKYBLUE (-6700 2825);
FORCEPROP 1 LAST VALUE 22UF
J 0
(-6700 2925);
DISPLAY 0.489362 (-6700 2925);
PAINT SKYBLUE (-6700 2925);
FORCEPROP 1 LAST PART_NUMBER CH622KMEB02
J 0
(-6700 2725);
DISPLAY 0.489362 (-6700 2725);
PAINT SKYBLUE (-6700 2725);
FORCEPROP 1 LAST VOLTAGE 4V
J 0
(-6700 2875);
DISPLAY 0.489362 (-6700 2875);
PAINT SKYBLUE (-6700 2875);
FORCEPROP 1 LAST PACK_TYPE C0402
J 0
(-6700 2675);
DISPLAY 0.489362 (-6700 2675);
PAINT SKYBLUE (-6700 2675);
FORCEPROP 2 LAST CDS_LIB pure_quanta
J 0
(-6750 2875);
PAINT MONO (-6750 2875);
DISPLAY INVISIBLE (-6750 2875);
FORCEPROP 1 LAST PATH I26
J 0
(-6700 3025);
DISPLAY 0.978723 (-6700 3025);
PAINT WHITE (-6700 3025);
DISPLAY INVISIBLE (-6700 3025);
FORCEADD Q_CAP..1
(-6300 2875);
FORCEPROP 1 LAST LOCATION C2190
J 0
(-6250 2975);
DISPLAY 0.489362 (-6250 2975);
PAINT SKYBLUE (-6250 2975);
FORCEPROP 2 LAST $SEC 1
J 0
(-6250 3075);
DISPLAY 0.680851 (-6250 3075);
PAINT MONO (-6250 3075);
DISPLAY INVISIBLE (-6250 3075);
FORCEPROP 2 LAST CDS_SEC 1
J 0
(-6250 3075);
DISPLAY 1.021277 (-6250 3075);
DISPLAY INVISIBLE (-6250 3075);
FORCEPROP 1 LASTPIN (-6300 2975) $PN 1
J 0
(-6290 2955);
DISPLAY 0.489362 (-6290 2955);
FORCEPROP 1 LASTPIN (-6300 2775) $PN 2
J 0
(-6290 2755);
DISPLAY 0.489362 (-6290 2755);
FORCEPROP 1 LAST MATERIAL X6S
J 0
(-6250 2775);
DISPLAY 0.489362 (-6250 2775);
PAINT SKYBLUE (-6250 2775);
FORCEPROP 1 LAST TOLERANCE 20%
J 0
(-6250 2825);
DISPLAY 0.489362 (-6250 2825);
PAINT SKYBLUE (-6250 2825);
FORCEPROP 1 LAST VALUE 22UF
J 0
(-6250 2925);
DISPLAY 0.489362 (-6250 2925);
PAINT SKYBLUE (-6250 2925);
FORCEPROP 1 LAST PART_NUMBER CH622KMEB02
J 0
(-6250 2725);
DISPLAY 0.489362 (-6250 2725);
PAINT SKYBLUE (-6250 2725);
FORCEPROP 1 LAST VOLTAGE 4V
J 0
(-6250 2875);
DISPLAY 0.489362 (-6250 2875);
PAINT SKYBLUE (-6250 2875);
FORCEPROP 1 LAST PACK_TYPE C0402
J 0
(-6250 2675);
DISPLAY 0.489362 (-6250 2675);
PAINT SKYBLUE (-6250 2675);
FORCEPROP 2 LAST CDS_LIB pure_quanta
J 0
(-6300 2875);
PAINT MONO (-6300 2875);
DISPLAY INVISIBLE (-6300 2875);
FORCEPROP 1 LAST PATH I27
J 0
(-6250 3025);
DISPLAY 0.978723 (-6250 3025);
PAINT WHITE (-6250 3025);
DISPLAY INVISIBLE (-6250 3025);
FORCEADD Q_CAP..1
(-6750 3675);
FORCEPROP 1 LAST LOCATION C2185
J 0
(-6700 3775);
DISPLAY 0.489362 (-6700 3775);
PAINT SKYBLUE (-6700 3775);
FORCEPROP 2 LAST $SEC 1
J 0
(-6700 3875);
DISPLAY 0.680851 (-6700 3875);
PAINT MONO (-6700 3875);
DISPLAY INVISIBLE (-6700 3875);
FORCEPROP 2 LAST CDS_SEC 1
J 0
(-6700 3875);
DISPLAY 1.021277 (-6700 3875);
DISPLAY INVISIBLE (-6700 3875);
FORCEPROP 1 LASTPIN (-6750 3775) $PN 1
J 0
(-6740 3755);
DISPLAY 0.489362 (-6740 3755);
FORCEPROP 1 LASTPIN (-6750 3575) $PN 2
J 0
(-6740 3555);
DISPLAY 0.489362 (-6740 3555);
FORCEPROP 1 LAST MATERIAL X6S
J 0
(-6700 3575);
DISPLAY 0.489362 (-6700 3575);
PAINT SKYBLUE (-6700 3575);
FORCEPROP 1 LAST TOLERANCE 20%
J 0
(-6700 3625);
DISPLAY 0.489362 (-6700 3625);
PAINT SKYBLUE (-6700 3625);
FORCEPROP 1 LAST VALUE 22UF
J 0
(-6700 3725);
DISPLAY 0.489362 (-6700 3725);
PAINT SKYBLUE (-6700 3725);
FORCEPROP 1 LAST PART_NUMBER CH622KMEB02
J 0
(-6700 3525);
DISPLAY 0.489362 (-6700 3525);
PAINT SKYBLUE (-6700 3525);
FORCEPROP 1 LAST VOLTAGE 4V
J 0
(-6700 3675);
DISPLAY 0.489362 (-6700 3675);
PAINT SKYBLUE (-6700 3675);
FORCEPROP 1 LAST PACK_TYPE C0402
J 0
(-6700 3475);
DISPLAY 0.489362 (-6700 3475);
PAINT SKYBLUE (-6700 3475);
FORCEPROP 2 LAST CDS_LIB pure_quanta
J 0
(-6750 3675);
PAINT MONO (-6750 3675);
DISPLAY INVISIBLE (-6750 3675);
FORCEPROP 1 LAST PATH I28
J 0
(-6700 3825);
DISPLAY 0.978723 (-6700 3825);
PAINT WHITE (-6700 3825);
DISPLAY INVISIBLE (-6700 3825);
FORCEADD Q_CAP..1
(-6300 3675);
FORCEPROP 1 LAST LOCATION C2189
J 0
(-6250 3775);
DISPLAY 0.489362 (-6250 3775);
PAINT SKYBLUE (-6250 3775);
FORCEPROP 2 LAST $SEC 1
J 0
(-6250 3875);
DISPLAY 0.680851 (-6250 3875);
PAINT MONO (-6250 3875);
DISPLAY INVISIBLE (-6250 3875);
FORCEPROP 2 LAST CDS_SEC 1
J 0
(-6250 3875);
DISPLAY 1.021277 (-6250 3875);
DISPLAY INVISIBLE (-6250 3875);
FORCEPROP 1 LASTPIN (-6300 3775) $PN 1
J 0
(-6290 3755);
DISPLAY 0.489362 (-6290 3755);
FORCEPROP 1 LASTPIN (-6300 3575) $PN 2
J 0
(-6290 3555);
DISPLAY 0.489362 (-6290 3555);
FORCEPROP 1 LAST MATERIAL X6S
J 0
(-6250 3575);
DISPLAY 0.489362 (-6250 3575);
PAINT SKYBLUE (-6250 3575);
FORCEPROP 1 LAST TOLERANCE 20%
J 0
(-6250 3625);
DISPLAY 0.489362 (-6250 3625);
PAINT SKYBLUE (-6250 3625);
FORCEPROP 1 LAST VALUE 22UF
J 0
(-6250 3725);
DISPLAY 0.489362 (-6250 3725);
PAINT SKYBLUE (-6250 3725);
FORCEPROP 1 LAST PART_NUMBER CH622KMEB02
J 0
(-6250 3525);
DISPLAY 0.489362 (-6250 3525);
PAINT SKYBLUE (-6250 3525);
FORCEPROP 1 LAST VOLTAGE 4V
J 0
(-6250 3675);
DISPLAY 0.489362 (-6250 3675);
PAINT SKYBLUE (-6250 3675);
FORCEPROP 1 LAST PACK_TYPE C0402
J 0
(-6250 3475);
DISPLAY 0.489362 (-6250 3475);
PAINT SKYBLUE (-6250 3475);
FORCEPROP 2 LAST CDS_LIB pure_quanta
J 0
(-6300 3675);
PAINT MONO (-6300 3675);
DISPLAY INVISIBLE (-6300 3675);
FORCEPROP 1 LAST PATH I29
J 0
(-6250 3825);
DISPLAY 0.978723 (-6250 3825);
PAINT WHITE (-6250 3825);
DISPLAY INVISIBLE (-6250 3825);
FORCEADD UNIVERSAL_POWER..1
(-9000 2350);
FORCEPROP 3 LASTPIN (-9000 2300) SIG_NAME PVDDCR_CPU0_P0\g
J 0
(-8990 2310);
DISPLAY 0.659574 (-8990 2310);
PAINT MONO (-8990 2310);
DISPLAY INVISIBLE (-8990 2310);
FORCEPROP 1 LAST HDL_POWER PVDDCR_CPU0_P0
J 1
(-9000 2400);
DISPLAY 0.489362 (-9000 2400);
PAINT GREEN (-9000 2400);
FORCEPROP 2 LAST CDS_LIB pure_quanta_power
J 0
(-9000 2350);
DISPLAY INVISIBLE (-9000 2350);
FORCEPROP 1 LAST PATH I3
J 0
(-8950 2375);
DISPLAY 0.872340 (-8950 2375);
PAINT AQUA (-8950 2375);
DISPLAY INVISIBLE (-8950 2375);
FORCEADD Q_CAP..1
(-4425 2075);
FORCEPROP 1 LAST LOCATION C2205
J 0
(-4375 2175);
DISPLAY 0.489362 (-4375 2175);
PAINT SKYBLUE (-4375 2175);
FORCEPROP 2 LAST $SEC 1
J 0
(-4375 2275);
DISPLAY 0.680851 (-4375 2275);
PAINT MONO (-4375 2275);
DISPLAY INVISIBLE (-4375 2275);
FORCEPROP 2 LAST CDS_SEC 1
J 0
(-4375 2275);
DISPLAY 1.021277 (-4375 2275);
DISPLAY INVISIBLE (-4375 2275);
FORCEPROP 1 LASTPIN (-4425 2175) $PN 1
J 0
(-4415 2155);
DISPLAY 0.489362 (-4415 2155);
FORCEPROP 1 LASTPIN (-4425 1975) $PN 2
J 0
(-4415 1955);
DISPLAY 0.489362 (-4415 1955);
FORCEPROP 1 LAST MATERIAL X6S
J 0
(-4375 1975);
DISPLAY 0.489362 (-4375 1975);
PAINT SKYBLUE (-4375 1975);
FORCEPROP 1 LAST TOLERANCE 20%
J 0
(-4375 2025);
DISPLAY 0.489362 (-4375 2025);
PAINT SKYBLUE (-4375 2025);
FORCEPROP 1 LAST VALUE 22UF
J 0
(-4375 2125);
DISPLAY 0.489362 (-4375 2125);
PAINT SKYBLUE (-4375 2125);
FORCEPROP 1 LAST PART_NUMBER CH622KMEB02
J 0
(-4375 1925);
DISPLAY 0.489362 (-4375 1925);
PAINT SKYBLUE (-4375 1925);
FORCEPROP 1 LAST VOLTAGE 4V
J 0
(-4375 2075);
DISPLAY 0.489362 (-4375 2075);
PAINT SKYBLUE (-4375 2075);
FORCEPROP 1 LAST PACK_TYPE C0402
J 0
(-4375 1875);
DISPLAY 0.489362 (-4375 1875);
PAINT SKYBLUE (-4375 1875);
FORCEPROP 2 LAST CDS_LIB pure_quanta
J 0
(-4425 2075);
PAINT MONO (-4425 2075);
DISPLAY INVISIBLE (-4425 2075);
FORCEPROP 1 LAST PATH I30
J 0
(-4375 2225);
DISPLAY 0.978723 (-4375 2225);
PAINT WHITE (-4375 2225);
DISPLAY INVISIBLE (-4375 2225);
FORCEADD Q_CAP..1
(-5850 2875);
FORCEPROP 1 LAST LOCATION C2193
J 0
(-5800 2975);
DISPLAY 0.489362 (-5800 2975);
PAINT SKYBLUE (-5800 2975);
FORCEPROP 2 LAST $SEC 1
J 0
(-5800 3075);
DISPLAY 0.680851 (-5800 3075);
PAINT MONO (-5800 3075);
DISPLAY INVISIBLE (-5800 3075);
FORCEPROP 2 LAST CDS_SEC 1
J 0
(-5800 3075);
DISPLAY 1.021277 (-5800 3075);
DISPLAY INVISIBLE (-5800 3075);
FORCEPROP 1 LASTPIN (-5850 2975) $PN 1
J 0
(-5840 2955);
DISPLAY 0.489362 (-5840 2955);
FORCEPROP 1 LASTPIN (-5850 2775) $PN 2
J 0
(-5840 2755);
DISPLAY 0.489362 (-5840 2755);
FORCEPROP 1 LAST MATERIAL X6S
J 0
(-5800 2775);
DISPLAY 0.489362 (-5800 2775);
PAINT SKYBLUE (-5800 2775);
FORCEPROP 1 LAST TOLERANCE 20%
J 0
(-5800 2825);
DISPLAY 0.489362 (-5800 2825);
PAINT SKYBLUE (-5800 2825);
FORCEPROP 1 LAST VALUE 22UF
J 0
(-5800 2925);
DISPLAY 0.489362 (-5800 2925);
PAINT SKYBLUE (-5800 2925);
FORCEPROP 1 LAST PART_NUMBER CH622KMEB02
J 0
(-5800 2725);
DISPLAY 0.489362 (-5800 2725);
PAINT SKYBLUE (-5800 2725);
FORCEPROP 1 LAST VOLTAGE 4V
J 0
(-5800 2875);
DISPLAY 0.489362 (-5800 2875);
PAINT SKYBLUE (-5800 2875);
FORCEPROP 1 LAST PACK_TYPE C0402
J 0
(-5800 2675);
DISPLAY 0.489362 (-5800 2675);
PAINT SKYBLUE (-5800 2675);
FORCEPROP 2 LAST CDS_LIB pure_quanta
J 0
(-5850 2875);
PAINT MONO (-5850 2875);
DISPLAY INVISIBLE (-5850 2875);
FORCEPROP 1 LAST PATH I31
J 0
(-5800 3025);
DISPLAY 0.978723 (-5800 3025);
PAINT WHITE (-5800 3025);
DISPLAY INVISIBLE (-5800 3025);
FORCEADD Q_CAP..1
(-5400 2875);
FORCEPROP 1 LAST LOCATION C2196
J 0
(-5350 2975);
DISPLAY 0.489362 (-5350 2975);
PAINT SKYBLUE (-5350 2975);
FORCEPROP 2 LAST $SEC 1
J 0
(-5350 3075);
DISPLAY 0.680851 (-5350 3075);
PAINT MONO (-5350 3075);
DISPLAY INVISIBLE (-5350 3075);
FORCEPROP 2 LAST CDS_SEC 1
J 0
(-5350 3075);
DISPLAY 1.021277 (-5350 3075);
DISPLAY INVISIBLE (-5350 3075);
FORCEPROP 1 LASTPIN (-5400 2975) $PN 1
J 0
(-5390 2955);
DISPLAY 0.489362 (-5390 2955);
FORCEPROP 1 LASTPIN (-5400 2775) $PN 2
J 0
(-5390 2755);
DISPLAY 0.489362 (-5390 2755);
FORCEPROP 1 LAST MATERIAL X6S
J 0
(-5350 2775);
DISPLAY 0.489362 (-5350 2775);
PAINT SKYBLUE (-5350 2775);
FORCEPROP 1 LAST TOLERANCE 20%
J 0
(-5350 2825);
DISPLAY 0.489362 (-5350 2825);
PAINT SKYBLUE (-5350 2825);
FORCEPROP 1 LAST VALUE 22UF
J 0
(-5350 2925);
DISPLAY 0.489362 (-5350 2925);
PAINT SKYBLUE (-5350 2925);
FORCEPROP 1 LAST PART_NUMBER CH622KMEB02
J 0
(-5350 2725);
DISPLAY 0.489362 (-5350 2725);
PAINT SKYBLUE (-5350 2725);
FORCEPROP 1 LAST VOLTAGE 4V
J 0
(-5350 2875);
DISPLAY 0.489362 (-5350 2875);
PAINT SKYBLUE (-5350 2875);
FORCEPROP 1 LAST PACK_TYPE C0402
J 0
(-5350 2675);
DISPLAY 0.489362 (-5350 2675);
PAINT SKYBLUE (-5350 2675);
FORCEPROP 2 LAST CDS_LIB pure_quanta
J 0
(-5400 2875);
PAINT MONO (-5400 2875);
DISPLAY INVISIBLE (-5400 2875);
FORCEPROP 1 LAST PATH I32
J 0
(-5350 3025);
DISPLAY 0.978723 (-5350 3025);
PAINT WHITE (-5350 3025);
DISPLAY INVISIBLE (-5350 3025);
FORCEADD Q_CAP..1
(-5850 3675);
FORCEPROP 1 LAST LOCATION C2192
J 0
(-5800 3775);
DISPLAY 0.489362 (-5800 3775);
PAINT SKYBLUE (-5800 3775);
FORCEPROP 2 LAST $SEC 1
J 0
(-5800 3875);
DISPLAY 0.680851 (-5800 3875);
PAINT MONO (-5800 3875);
DISPLAY INVISIBLE (-5800 3875);
FORCEPROP 2 LAST CDS_SEC 1
J 0
(-5800 3875);
DISPLAY 1.021277 (-5800 3875);
DISPLAY INVISIBLE (-5800 3875);
FORCEPROP 1 LASTPIN (-5850 3775) $PN 1
J 0
(-5840 3755);
DISPLAY 0.489362 (-5840 3755);
FORCEPROP 1 LASTPIN (-5850 3575) $PN 2
J 0
(-5840 3555);
DISPLAY 0.489362 (-5840 3555);
FORCEPROP 1 LAST MATERIAL X6S
J 0
(-5800 3575);
DISPLAY 0.489362 (-5800 3575);
PAINT SKYBLUE (-5800 3575);
FORCEPROP 1 LAST TOLERANCE 20%
J 0
(-5800 3625);
DISPLAY 0.489362 (-5800 3625);
PAINT SKYBLUE (-5800 3625);
FORCEPROP 1 LAST VALUE 22UF
J 0
(-5800 3725);
DISPLAY 0.489362 (-5800 3725);
PAINT SKYBLUE (-5800 3725);
FORCEPROP 1 LAST PART_NUMBER CH622KMEB02
J 0
(-5800 3525);
DISPLAY 0.489362 (-5800 3525);
PAINT SKYBLUE (-5800 3525);
FORCEPROP 1 LAST VOLTAGE 4V
J 0
(-5800 3675);
DISPLAY 0.489362 (-5800 3675);
PAINT SKYBLUE (-5800 3675);
FORCEPROP 1 LAST PACK_TYPE C0402
J 0
(-5800 3475);
DISPLAY 0.489362 (-5800 3475);
PAINT SKYBLUE (-5800 3475);
FORCEPROP 2 LAST CDS_LIB pure_quanta
J 0
(-5850 3675);
PAINT MONO (-5850 3675);
DISPLAY INVISIBLE (-5850 3675);
FORCEPROP 1 LAST PATH I33
J 0
(-5800 3825);
DISPLAY 0.978723 (-5800 3825);
PAINT WHITE (-5800 3825);
DISPLAY INVISIBLE (-5800 3825);
FORCEADD Q_CAP..1
(-5400 3675);
FORCEPROP 1 LAST LOCATION C2195
J 0
(-5350 3775);
DISPLAY 0.489362 (-5350 3775);
PAINT SKYBLUE (-5350 3775);
FORCEPROP 2 LAST $SEC 1
J 0
(-5350 3875);
DISPLAY 0.680851 (-5350 3875);
PAINT MONO (-5350 3875);
DISPLAY INVISIBLE (-5350 3875);
FORCEPROP 2 LAST CDS_SEC 1
J 0
(-5350 3875);
DISPLAY 1.021277 (-5350 3875);
DISPLAY INVISIBLE (-5350 3875);
FORCEPROP 1 LASTPIN (-5400 3775) $PN 1
J 0
(-5390 3755);
DISPLAY 0.489362 (-5390 3755);
FORCEPROP 1 LASTPIN (-5400 3575) $PN 2
J 0
(-5390 3555);
DISPLAY 0.489362 (-5390 3555);
FORCEPROP 1 LAST MATERIAL X6S
J 0
(-5350 3575);
DISPLAY 0.489362 (-5350 3575);
PAINT SKYBLUE (-5350 3575);
FORCEPROP 1 LAST TOLERANCE 20%
J 0
(-5350 3625);
DISPLAY 0.489362 (-5350 3625);
PAINT SKYBLUE (-5350 3625);
FORCEPROP 1 LAST VALUE 22UF
J 0
(-5350 3725);
DISPLAY 0.489362 (-5350 3725);
PAINT SKYBLUE (-5350 3725);
FORCEPROP 1 LAST PART_NUMBER CH622KMEB02
J 0
(-5350 3525);
DISPLAY 0.489362 (-5350 3525);
PAINT SKYBLUE (-5350 3525);
FORCEPROP 1 LAST VOLTAGE 4V
J 0
(-5350 3675);
DISPLAY 0.489362 (-5350 3675);
PAINT SKYBLUE (-5350 3675);
FORCEPROP 1 LAST PACK_TYPE C0402
J 0
(-5350 3475);
DISPLAY 0.489362 (-5350 3475);
PAINT SKYBLUE (-5350 3475);
FORCEPROP 2 LAST CDS_LIB pure_quanta
J 0
(-5400 3675);
PAINT MONO (-5400 3675);
DISPLAY INVISIBLE (-5400 3675);
FORCEPROP 1 LAST PATH I34
J 0
(-5350 3825);
DISPLAY 0.978723 (-5350 3825);
PAINT WHITE (-5350 3825);
DISPLAY INVISIBLE (-5350 3825);
FORCEADD UNIVERSAL_GND..1
(-5000 2500);
FORCEPROP 3 LASTPIN (-5000 2550) SIG_NAME GND\g
J 0
(-4990 2560);
DISPLAY 0.659574 (-4990 2560);
PAINT MONO (-4990 2560);
DISPLAY INVISIBLE (-4990 2560);
FORCEPROP 2 LAST CDS_LIB pure_quanta_power
J 0
(-5000 2500);
PAINT MONO (-5000 2500);
DISPLAY INVISIBLE (-5000 2500);
FORCEPROP 1 LAST PATH I35
J 0
(-4925 2500);
DISPLAY 0.872340 (-4925 2500);
PAINT AQUA (-4925 2500);
DISPLAY INVISIBLE (-4925 2500);
FORCEPROP 1 LAST HDL_POWER GND
J 1
(-4975 2425);
DISPLAY 0.872340 (-4975 2425);
PAINT GREEN (-4975 2425);
DISPLAY INVISIBLE (-4975 2425);
FORCEADD Q_CAP..1
(-5000 2875);
FORCEPROP 1 LAST LOCATION C2199
J 0
(-4950 2975);
DISPLAY 0.489362 (-4950 2975);
PAINT SKYBLUE (-4950 2975);
FORCEPROP 2 LAST $SEC 1
J 0
(-4950 3075);
DISPLAY 0.680851 (-4950 3075);
PAINT MONO (-4950 3075);
DISPLAY INVISIBLE (-4950 3075);
FORCEPROP 2 LAST CDS_SEC 1
J 0
(-4950 3075);
DISPLAY 1.021277 (-4950 3075);
DISPLAY INVISIBLE (-4950 3075);
FORCEPROP 1 LASTPIN (-5000 2975) $PN 1
J 0
(-4990 2955);
DISPLAY 0.489362 (-4990 2955);
FORCEPROP 1 LASTPIN (-5000 2775) $PN 2
J 0
(-4990 2755);
DISPLAY 0.489362 (-4990 2755);
FORCEPROP 1 LAST MATERIAL X6S
J 0
(-4950 2775);
DISPLAY 0.489362 (-4950 2775);
PAINT SKYBLUE (-4950 2775);
FORCEPROP 1 LAST TOLERANCE 20%
J 0
(-4950 2825);
DISPLAY 0.489362 (-4950 2825);
PAINT SKYBLUE (-4950 2825);
FORCEPROP 1 LAST VALUE 22UF
J 0
(-4950 2925);
DISPLAY 0.489362 (-4950 2925);
PAINT SKYBLUE (-4950 2925);
FORCEPROP 1 LAST PART_NUMBER CH622KMEB02
J 0
(-4950 2725);
DISPLAY 0.489362 (-4950 2725);
PAINT SKYBLUE (-4950 2725);
FORCEPROP 1 LAST VOLTAGE 4V
J 0
(-4950 2875);
DISPLAY 0.489362 (-4950 2875);
PAINT SKYBLUE (-4950 2875);
FORCEPROP 1 LAST PACK_TYPE C0402
J 0
(-4950 2675);
DISPLAY 0.489362 (-4950 2675);
PAINT SKYBLUE (-4950 2675);
FORCEPROP 2 LAST CDS_LIB pure_quanta
J 0
(-5000 2875);
PAINT MONO (-5000 2875);
DISPLAY INVISIBLE (-5000 2875);
FORCEPROP 1 LAST PATH I36
J 0
(-4950 3025);
DISPLAY 0.978723 (-4950 3025);
PAINT WHITE (-4950 3025);
DISPLAY INVISIBLE (-4950 3025);
FORCEADD UNIVERSAL_POWER..1
(-4425 2350);
FORCEPROP 3 LASTPIN (-4425 2300) SIG_NAME PVDDCR_CPU1_P0\g
J 0
(-4415 2310);
DISPLAY 0.659574 (-4415 2310);
PAINT MONO (-4415 2310);
DISPLAY INVISIBLE (-4415 2310);
FORCEPROP 1 LAST HDL_POWER PVDDCR_CPU1_P0
J 1
(-4425 2400);
DISPLAY 0.489362 (-4425 2400);
PAINT GREEN (-4425 2400);
FORCEPROP 2 LAST CDS_LIB pure_quanta_power
J 0
(-4425 2350);
DISPLAY INVISIBLE (-4425 2350);
FORCEPROP 1 LAST PATH I37
J 0
(-4375 2375);
DISPLAY 0.872340 (-4375 2375);
PAINT AQUA (-4375 2375);
DISPLAY INVISIBLE (-4375 2375);
FORCEADD Q_CAP..1
(-4425 2875);
FORCEPROP 1 LAST LOCATION C2204
J 0
(-4375 2975);
DISPLAY 0.489362 (-4375 2975);
PAINT SKYBLUE (-4375 2975);
FORCEPROP 2 LAST $SEC 1
J 0
(-4375 3075);
DISPLAY 0.680851 (-4375 3075);
PAINT MONO (-4375 3075);
DISPLAY INVISIBLE (-4375 3075);
FORCEPROP 2 LAST CDS_SEC 1
J 0
(-4375 3075);
DISPLAY 1.021277 (-4375 3075);
DISPLAY INVISIBLE (-4375 3075);
FORCEPROP 1 LASTPIN (-4425 2975) $PN 1
J 0
(-4415 2955);
DISPLAY 0.489362 (-4415 2955);
FORCEPROP 1 LASTPIN (-4425 2775) $PN 2
J 0
(-4415 2755);
DISPLAY 0.489362 (-4415 2755);
FORCEPROP 1 LAST MATERIAL X6S
J 0
(-4375 2775);
DISPLAY 0.489362 (-4375 2775);
PAINT SKYBLUE (-4375 2775);
FORCEPROP 1 LAST TOLERANCE 20%
J 0
(-4375 2825);
DISPLAY 0.489362 (-4375 2825);
PAINT SKYBLUE (-4375 2825);
FORCEPROP 1 LAST VALUE 22UF
J 0
(-4375 2925);
DISPLAY 0.489362 (-4375 2925);
PAINT SKYBLUE (-4375 2925);
FORCEPROP 1 LAST PART_NUMBER CH622KMEB02
J 0
(-4375 2725);
DISPLAY 0.489362 (-4375 2725);
PAINT SKYBLUE (-4375 2725);
FORCEPROP 1 LAST VOLTAGE 4V
J 0
(-4375 2875);
DISPLAY 0.489362 (-4375 2875);
PAINT SKYBLUE (-4375 2875);
FORCEPROP 1 LAST PACK_TYPE C0402
J 0
(-4375 2675);
DISPLAY 0.489362 (-4375 2675);
PAINT SKYBLUE (-4375 2675);
FORCEPROP 2 LAST CDS_LIB pure_quanta
J 0
(-4425 2875);
PAINT MONO (-4425 2875);
DISPLAY INVISIBLE (-4425 2875);
FORCEPROP 1 LAST PATH I38
J 0
(-4375 3025);
DISPLAY 0.978723 (-4375 3025);
PAINT WHITE (-4375 3025);
DISPLAY INVISIBLE (-4375 3025);
FORCEADD UNIVERSAL_GND..1
(-5000 3300);
FORCEPROP 3 LASTPIN (-5000 3350) SIG_NAME GND\g
J 0
(-4990 3360);
DISPLAY 0.659574 (-4990 3360);
PAINT MONO (-4990 3360);
DISPLAY INVISIBLE (-4990 3360);
FORCEPROP 2 LAST CDS_LIB pure_quanta_power
J 0
(-5000 3300);
PAINT MONO (-5000 3300);
DISPLAY INVISIBLE (-5000 3300);
FORCEPROP 1 LAST PATH I39
J 0
(-4925 3300);
DISPLAY 0.872340 (-4925 3300);
PAINT AQUA (-4925 3300);
DISPLAY INVISIBLE (-4925 3300);
FORCEPROP 1 LAST HDL_POWER GND
J 1
(-4975 3225);
DISPLAY 0.872340 (-4975 3225);
PAINT GREEN (-4975 3225);
DISPLAY INVISIBLE (-4975 3225);
FORCEADD Q_CAP..1
(-9000 2875);
FORCEPROP 1 LAST LOCATION C2166
J 0
(-8950 2975);
DISPLAY 0.489362 (-8950 2975);
PAINT SKYBLUE (-8950 2975);
FORCEPROP 2 LAST $SEC 1
J 0
(-8950 3075);
DISPLAY 0.680851 (-8950 3075);
PAINT MONO (-8950 3075);
DISPLAY INVISIBLE (-8950 3075);
FORCEPROP 2 LAST CDS_SEC 1
J 0
(-8950 3075);
DISPLAY 1.021277 (-8950 3075);
DISPLAY INVISIBLE (-8950 3075);
FORCEPROP 1 LASTPIN (-9000 2975) $PN 1
J 0
(-8990 2955);
DISPLAY 0.489362 (-8990 2955);
FORCEPROP 1 LASTPIN (-9000 2775) $PN 2
J 0
(-8990 2755);
DISPLAY 0.489362 (-8990 2755);
FORCEPROP 1 LAST MATERIAL X6S
J 0
(-8950 2775);
DISPLAY 0.489362 (-8950 2775);
PAINT SKYBLUE (-8950 2775);
FORCEPROP 1 LAST TOLERANCE 20%
J 0
(-8950 2825);
DISPLAY 0.489362 (-8950 2825);
PAINT SKYBLUE (-8950 2825);
FORCEPROP 1 LAST VALUE 22UF
J 0
(-8950 2925);
DISPLAY 0.489362 (-8950 2925);
PAINT SKYBLUE (-8950 2925);
FORCEPROP 1 LAST PART_NUMBER CH622KMEB02
J 0
(-8950 2725);
DISPLAY 0.489362 (-8950 2725);
PAINT SKYBLUE (-8950 2725);
FORCEPROP 1 LAST VOLTAGE 4V
J 0
(-8950 2875);
DISPLAY 0.489362 (-8950 2875);
PAINT SKYBLUE (-8950 2875);
FORCEPROP 1 LAST PACK_TYPE C0402
J 0
(-8950 2675);
DISPLAY 0.489362 (-8950 2675);
PAINT SKYBLUE (-8950 2675);
FORCEPROP 2 LAST CDS_LIB pure_quanta
J 0
(-9000 2875);
PAINT MONO (-9000 2875);
DISPLAY INVISIBLE (-9000 2875);
FORCEPROP 1 LAST PATH I4
J 0
(-8950 3025);
DISPLAY 0.978723 (-8950 3025);
PAINT WHITE (-8950 3025);
DISPLAY INVISIBLE (-8950 3025);
FORCEADD Q_CAP..1
(-5000 3675);
FORCEPROP 1 LAST LOCATION C2198
J 0
(-4950 3775);
DISPLAY 0.489362 (-4950 3775);
PAINT SKYBLUE (-4950 3775);
FORCEPROP 2 LAST $SEC 1
J 0
(-4950 3875);
DISPLAY 0.680851 (-4950 3875);
PAINT MONO (-4950 3875);
DISPLAY INVISIBLE (-4950 3875);
FORCEPROP 2 LAST CDS_SEC 1
J 0
(-4950 3875);
DISPLAY 1.021277 (-4950 3875);
DISPLAY INVISIBLE (-4950 3875);
FORCEPROP 1 LASTPIN (-5000 3775) $PN 1
J 0
(-4990 3755);
DISPLAY 0.489362 (-4990 3755);
FORCEPROP 1 LASTPIN (-5000 3575) $PN 2
J 0
(-4990 3555);
DISPLAY 0.489362 (-4990 3555);
FORCEPROP 1 LAST MATERIAL X6S
J 0
(-4950 3575);
DISPLAY 0.489362 (-4950 3575);
PAINT SKYBLUE (-4950 3575);
FORCEPROP 1 LAST TOLERANCE 20%
J 0
(-4950 3625);
DISPLAY 0.489362 (-4950 3625);
PAINT SKYBLUE (-4950 3625);
FORCEPROP 1 LAST VALUE 22UF
J 0
(-4950 3725);
DISPLAY 0.489362 (-4950 3725);
PAINT SKYBLUE (-4950 3725);
FORCEPROP 1 LAST PART_NUMBER CH622KMEB02
J 0
(-4950 3525);
DISPLAY 0.489362 (-4950 3525);
PAINT SKYBLUE (-4950 3525);
FORCEPROP 1 LAST VOLTAGE 4V
J 0
(-4950 3675);
DISPLAY 0.489362 (-4950 3675);
PAINT SKYBLUE (-4950 3675);
FORCEPROP 1 LAST PACK_TYPE C0402
J 0
(-4950 3475);
DISPLAY 0.489362 (-4950 3475);
PAINT SKYBLUE (-4950 3475);
FORCEPROP 2 LAST CDS_LIB pure_quanta
J 0
(-5000 3675);
PAINT MONO (-5000 3675);
DISPLAY INVISIBLE (-5000 3675);
FORCEPROP 1 LAST PATH I40
J 0
(-4950 3825);
DISPLAY 0.978723 (-4950 3825);
PAINT WHITE (-4950 3825);
DISPLAY INVISIBLE (-4950 3825);
FORCEADD UNIVERSAL_GND..1
(-5000 4100);
FORCEPROP 3 LASTPIN (-5000 4150) SIG_NAME GND\g
J 0
(-4990 4160);
DISPLAY 0.659574 (-4990 4160);
PAINT MONO (-4990 4160);
DISPLAY INVISIBLE (-4990 4160);
FORCEPROP 2 LAST CDS_LIB pure_quanta_power
J 0
(-5000 4100);
PAINT MONO (-5000 4100);
DISPLAY INVISIBLE (-5000 4100);
FORCEPROP 1 LAST PATH I41
J 0
(-4925 4100);
DISPLAY 0.872340 (-4925 4100);
PAINT AQUA (-4925 4100);
DISPLAY INVISIBLE (-4925 4100);
FORCEPROP 1 LAST HDL_POWER GND
J 1
(-4975 4025);
DISPLAY 0.872340 (-4975 4025);
PAINT GREEN (-4975 4025);
DISPLAY INVISIBLE (-4975 4025);
FORCEADD UNIVERSAL_POWER..1
(-4425 3150);
FORCEPROP 3 LASTPIN (-4425 3100) SIG_NAME PVDDCR_CPU1_P0\g
J 0
(-4415 3110);
DISPLAY 0.659574 (-4415 3110);
PAINT MONO (-4415 3110);
DISPLAY INVISIBLE (-4415 3110);
FORCEPROP 1 LAST HDL_POWER PVDDCR_CPU1_P0
J 1
(-4425 3200);
DISPLAY 0.489362 (-4425 3200);
PAINT GREEN (-4425 3200);
FORCEPROP 2 LAST CDS_LIB pure_quanta_power
J 0
(-4425 3150);
DISPLAY INVISIBLE (-4425 3150);
FORCEPROP 1 LAST PATH I42
J 0
(-4375 3175);
DISPLAY 0.872340 (-4375 3175);
PAINT AQUA (-4375 3175);
DISPLAY INVISIBLE (-4375 3175);
FORCEADD Q_CAP..1
(-4425 3675);
FORCEPROP 1 LAST LOCATION C2203
J 0
(-4375 3775);
DISPLAY 0.489362 (-4375 3775);
PAINT SKYBLUE (-4375 3775);
FORCEPROP 2 LAST $SEC 1
J 0
(-4375 3875);
DISPLAY 0.680851 (-4375 3875);
PAINT MONO (-4375 3875);
DISPLAY INVISIBLE (-4375 3875);
FORCEPROP 2 LAST CDS_SEC 1
J 0
(-4375 3875);
DISPLAY 1.021277 (-4375 3875);
DISPLAY INVISIBLE (-4375 3875);
FORCEPROP 1 LASTPIN (-4425 3775) $PN 1
J 0
(-4415 3755);
DISPLAY 0.489362 (-4415 3755);
FORCEPROP 1 LASTPIN (-4425 3575) $PN 2
J 0
(-4415 3555);
DISPLAY 0.489362 (-4415 3555);
FORCEPROP 1 LAST MATERIAL X6S
J 0
(-4375 3575);
DISPLAY 0.489362 (-4375 3575);
PAINT SKYBLUE (-4375 3575);
FORCEPROP 1 LAST TOLERANCE 20%
J 0
(-4375 3625);
DISPLAY 0.489362 (-4375 3625);
PAINT SKYBLUE (-4375 3625);
FORCEPROP 1 LAST VALUE 22UF
J 0
(-4375 3725);
DISPLAY 0.489362 (-4375 3725);
PAINT SKYBLUE (-4375 3725);
FORCEPROP 1 LAST PART_NUMBER CH622KMEB02
J 0
(-4375 3525);
DISPLAY 0.489362 (-4375 3525);
PAINT SKYBLUE (-4375 3525);
FORCEPROP 1 LAST VOLTAGE 4V
J 0
(-4375 3675);
DISPLAY 0.489362 (-4375 3675);
PAINT SKYBLUE (-4375 3675);
FORCEPROP 1 LAST PACK_TYPE C0402
J 0
(-4375 3475);
DISPLAY 0.489362 (-4375 3475);
PAINT SKYBLUE (-4375 3475);
FORCEPROP 2 LAST CDS_LIB pure_quanta
J 0
(-4425 3675);
PAINT MONO (-4425 3675);
DISPLAY INVISIBLE (-4425 3675);
FORCEPROP 1 LAST PATH I43
J 0
(-4375 3825);
DISPLAY 0.978723 (-4375 3825);
PAINT WHITE (-4375 3825);
DISPLAY INVISIBLE (-4375 3825);
FORCEADD UNIVERSAL_POWER..1
(-4425 3950);
FORCEPROP 3 LASTPIN (-4425 3900) SIG_NAME PVDDCR_CPU1_P0\g
J 0
(-4415 3910);
DISPLAY 0.659574 (-4415 3910);
PAINT MONO (-4415 3910);
DISPLAY INVISIBLE (-4415 3910);
FORCEPROP 1 LAST HDL_POWER PVDDCR_CPU1_P0
J 1
(-4425 4000);
DISPLAY 0.489362 (-4425 4000);
PAINT GREEN (-4425 4000);
FORCEPROP 2 LAST CDS_LIB pure_quanta_power
J 0
(-4425 3950);
DISPLAY INVISIBLE (-4425 3950);
FORCEPROP 1 LAST PATH I44
J 0
(-4375 3975);
DISPLAY 0.872340 (-4375 3975);
PAINT AQUA (-4375 3975);
DISPLAY INVISIBLE (-4375 3975);
FORCEADD Q_CAP..1
(-8100 4475);
FORCEPROP 1 LAST LOCATION C1922
J 0
(-8050 4575);
DISPLAY 0.489362 (-8050 4575);
PAINT SKYBLUE (-8050 4575);
FORCEPROP 2 LAST $SEC 1
J 0
(-8050 4675);
DISPLAY 0.680851 (-8050 4675);
PAINT MONO (-8050 4675);
DISPLAY INVISIBLE (-8050 4675);
FORCEPROP 2 LAST CDS_SEC 1
J 0
(-8050 4675);
DISPLAY 1.021277 (-8050 4675);
DISPLAY INVISIBLE (-8050 4675);
FORCEPROP 1 LASTPIN (-8100 4575) $PN 1
J 0
(-8090 4555);
DISPLAY 0.489362 (-8090 4555);
FORCEPROP 1 LASTPIN (-8100 4375) $PN 2
J 0
(-8090 4355);
DISPLAY 0.489362 (-8090 4355);
FORCEPROP 1 LAST MATERIAL X6S
J 0
(-8050 4375);
DISPLAY 0.489362 (-8050 4375);
PAINT SKYBLUE (-8050 4375);
FORCEPROP 1 LAST TOLERANCE 20%
J 0
(-8050 4425);
DISPLAY 0.489362 (-8050 4425);
PAINT SKYBLUE (-8050 4425);
FORCEPROP 1 LAST VALUE 22UF
J 0
(-8050 4525);
DISPLAY 0.489362 (-8050 4525);
PAINT SKYBLUE (-8050 4525);
FORCEPROP 1 LAST PART_NUMBER CH622KMEB02
J 0
(-8050 4325);
DISPLAY 0.489362 (-8050 4325);
PAINT SKYBLUE (-8050 4325);
FORCEPROP 1 LAST VOLTAGE 4V
J 0
(-8050 4475);
DISPLAY 0.489362 (-8050 4475);
PAINT SKYBLUE (-8050 4475);
FORCEPROP 1 LAST PACK_TYPE C0402
J 0
(-8050 4275);
DISPLAY 0.489362 (-8050 4275);
PAINT SKYBLUE (-8050 4275);
FORCEPROP 2 LAST CDS_LIB pure_quanta
J 0
(-8100 4475);
PAINT MONO (-8100 4475);
DISPLAY INVISIBLE (-8100 4475);
FORCEPROP 1 LAST PATH I45
J 0
(-8050 4625);
DISPLAY 0.978723 (-8050 4625);
PAINT WHITE (-8050 4625);
DISPLAY INVISIBLE (-8050 4625);
FORCEADD Q_CAP..1
(-7650 4475);
FORCEPROP 1 LAST LOCATION C263
J 0
(-7600 4575);
DISPLAY 0.489362 (-7600 4575);
PAINT SKYBLUE (-7600 4575);
FORCEPROP 2 LAST $SEC 1
J 0
(-7600 4675);
DISPLAY 0.680851 (-7600 4675);
PAINT MONO (-7600 4675);
DISPLAY INVISIBLE (-7600 4675);
FORCEPROP 2 LAST CDS_SEC 1
J 0
(-7600 4675);
DISPLAY 1.021277 (-7600 4675);
DISPLAY INVISIBLE (-7600 4675);
FORCEPROP 1 LASTPIN (-7650 4575) $PN 1
J 0
(-7640 4555);
DISPLAY 0.489362 (-7640 4555);
FORCEPROP 1 LASTPIN (-7650 4375) $PN 2
J 0
(-7640 4355);
DISPLAY 0.489362 (-7640 4355);
FORCEPROP 1 LAST MATERIAL X6S
J 0
(-7600 4375);
DISPLAY 0.489362 (-7600 4375);
PAINT SKYBLUE (-7600 4375);
FORCEPROP 1 LAST TOLERANCE 20%
J 0
(-7600 4425);
DISPLAY 0.489362 (-7600 4425);
PAINT SKYBLUE (-7600 4425);
FORCEPROP 1 LAST VALUE 22UF
J 0
(-7600 4525);
DISPLAY 0.489362 (-7600 4525);
PAINT SKYBLUE (-7600 4525);
FORCEPROP 1 LAST PART_NUMBER CH622KMEB02
J 0
(-7600 4325);
DISPLAY 0.489362 (-7600 4325);
PAINT SKYBLUE (-7600 4325);
FORCEPROP 1 LAST VOLTAGE 4V
J 0
(-7600 4475);
DISPLAY 0.489362 (-7600 4475);
PAINT SKYBLUE (-7600 4475);
FORCEPROP 1 LAST PACK_TYPE C0402
J 0
(-7600 4275);
DISPLAY 0.489362 (-7600 4275);
PAINT SKYBLUE (-7600 4275);
FORCEPROP 2 LAST CDS_LIB pure_quanta
J 0
(-7650 4475);
PAINT MONO (-7650 4475);
DISPLAY INVISIBLE (-7650 4475);
FORCEPROP 1 LAST PATH I46
J 0
(-7600 4625);
DISPLAY 0.978723 (-7600 4625);
PAINT WHITE (-7600 4625);
DISPLAY INVISIBLE (-7600 4625);
FORCEADD Q_CAP..1
(-8100 5250);
FORCEPROP 1 LAST LOCATION C4178
J 0
(-8050 5350);
DISPLAY 0.489362 (-8050 5350);
PAINT SKYBLUE (-8050 5350);
FORCEPROP 2 LAST $SEC 1
J 0
(-8050 5450);
DISPLAY 0.680851 (-8050 5450);
PAINT MONO (-8050 5450);
DISPLAY INVISIBLE (-8050 5450);
FORCEPROP 2 LAST CDS_SEC 1
J 0
(-8050 5450);
DISPLAY 1.021277 (-8050 5450);
DISPLAY INVISIBLE (-8050 5450);
FORCEPROP 1 LASTPIN (-8100 5350) $PN 1
J 0
(-8090 5330);
DISPLAY 0.489362 (-8090 5330);
FORCEPROP 1 LASTPIN (-8100 5150) $PN 2
J 0
(-8090 5130);
DISPLAY 0.489362 (-8090 5130);
FORCEPROP 1 LAST MATERIAL X6S
J 0
(-8050 5150);
DISPLAY 0.489362 (-8050 5150);
PAINT SKYBLUE (-8050 5150);
FORCEPROP 1 LAST TOLERANCE 20%
J 0
(-8050 5200);
DISPLAY 0.489362 (-8050 5200);
PAINT SKYBLUE (-8050 5200);
FORCEPROP 1 LAST VALUE 22UF
J 0
(-8050 5300);
DISPLAY 0.489362 (-8050 5300);
PAINT SKYBLUE (-8050 5300);
FORCEPROP 1 LAST PART_NUMBER CH622KMEB02
J 0
(-8050 5100);
DISPLAY 0.489362 (-8050 5100);
PAINT SKYBLUE (-8050 5100);
FORCEPROP 1 LAST VOLTAGE 4V
J 0
(-8050 5250);
DISPLAY 0.489362 (-8050 5250);
PAINT SKYBLUE (-8050 5250);
FORCEPROP 1 LAST PACK_TYPE C0402
J 0
(-8050 5050);
DISPLAY 0.489362 (-8050 5050);
PAINT SKYBLUE (-8050 5050);
FORCEPROP 2 LAST CDS_LIB pure_quanta
J 0
(-8100 5250);
PAINT MONO (-8100 5250);
DISPLAY INVISIBLE (-8100 5250);
FORCEPROP 1 LAST PATH I47
J 0
(-8050 5400);
DISPLAY 0.978723 (-8050 5400);
PAINT WHITE (-8050 5400);
DISPLAY INVISIBLE (-8050 5400);
FORCEADD Q_CAP..1
(-7650 5250);
FORCEPROP 1 LAST LOCATION C4179
J 0
(-7600 5350);
DISPLAY 0.489362 (-7600 5350);
PAINT SKYBLUE (-7600 5350);
FORCEPROP 2 LAST $SEC 1
J 0
(-7600 5450);
DISPLAY 0.680851 (-7600 5450);
PAINT MONO (-7600 5450);
DISPLAY INVISIBLE (-7600 5450);
FORCEPROP 2 LAST CDS_SEC 1
J 0
(-7600 5450);
DISPLAY 1.021277 (-7600 5450);
DISPLAY INVISIBLE (-7600 5450);
FORCEPROP 1 LASTPIN (-7650 5350) $PN 1
J 0
(-7640 5330);
DISPLAY 0.489362 (-7640 5330);
FORCEPROP 1 LASTPIN (-7650 5150) $PN 2
J 0
(-7640 5130);
DISPLAY 0.489362 (-7640 5130);
FORCEPROP 1 LAST MATERIAL X6S
J 0
(-7600 5150);
DISPLAY 0.489362 (-7600 5150);
PAINT SKYBLUE (-7600 5150);
FORCEPROP 1 LAST TOLERANCE 20%
J 0
(-7600 5200);
DISPLAY 0.489362 (-7600 5200);
PAINT SKYBLUE (-7600 5200);
FORCEPROP 1 LAST VALUE 22UF
J 0
(-7600 5300);
DISPLAY 0.489362 (-7600 5300);
PAINT SKYBLUE (-7600 5300);
FORCEPROP 1 LAST PART_NUMBER CH622KMEB02
J 0
(-7600 5100);
DISPLAY 0.489362 (-7600 5100);
PAINT SKYBLUE (-7600 5100);
FORCEPROP 1 LAST VOLTAGE 4V
J 0
(-7600 5250);
DISPLAY 0.489362 (-7600 5250);
PAINT SKYBLUE (-7600 5250);
FORCEPROP 1 LAST PACK_TYPE C0402
J 0
(-7600 5050);
DISPLAY 0.489362 (-7600 5050);
PAINT SKYBLUE (-7600 5050);
FORCEPROP 2 LAST CDS_LIB pure_quanta
J 0
(-7650 5250);
PAINT MONO (-7650 5250);
DISPLAY INVISIBLE (-7650 5250);
FORCEPROP 1 LAST PATH I48
J 0
(-7600 5400);
DISPLAY 0.978723 (-7600 5400);
PAINT WHITE (-7600 5400);
DISPLAY INVISIBLE (-7600 5400);
FORCEADD Q_CAP..1
(-7200 4475);
FORCEPROP 1 LAST LOCATION C268
J 0
(-7150 4575);
DISPLAY 0.489362 (-7150 4575);
PAINT SKYBLUE (-7150 4575);
FORCEPROP 2 LAST $SEC 1
J 0
(-7150 4675);
DISPLAY 0.680851 (-7150 4675);
PAINT MONO (-7150 4675);
DISPLAY INVISIBLE (-7150 4675);
FORCEPROP 2 LAST CDS_SEC 1
J 0
(-7150 4675);
DISPLAY 1.021277 (-7150 4675);
DISPLAY INVISIBLE (-7150 4675);
FORCEPROP 1 LASTPIN (-7200 4575) $PN 1
J 0
(-7190 4555);
DISPLAY 0.489362 (-7190 4555);
FORCEPROP 1 LASTPIN (-7200 4375) $PN 2
J 0
(-7190 4355);
DISPLAY 0.489362 (-7190 4355);
FORCEPROP 1 LAST MATERIAL X6S
J 0
(-7150 4375);
DISPLAY 0.489362 (-7150 4375);
PAINT SKYBLUE (-7150 4375);
FORCEPROP 1 LAST TOLERANCE 20%
J 0
(-7150 4425);
DISPLAY 0.489362 (-7150 4425);
PAINT SKYBLUE (-7150 4425);
FORCEPROP 1 LAST VALUE 22UF
J 0
(-7150 4525);
DISPLAY 0.489362 (-7150 4525);
PAINT SKYBLUE (-7150 4525);
FORCEPROP 1 LAST PART_NUMBER CH622KMEB02
J 0
(-7150 4325);
DISPLAY 0.489362 (-7150 4325);
PAINT SKYBLUE (-7150 4325);
FORCEPROP 1 LAST VOLTAGE 4V
J 0
(-7150 4475);
DISPLAY 0.489362 (-7150 4475);
PAINT SKYBLUE (-7150 4475);
FORCEPROP 1 LAST PACK_TYPE C0402
J 0
(-7150 4275);
DISPLAY 0.489362 (-7150 4275);
PAINT SKYBLUE (-7150 4275);
FORCEPROP 2 LAST CDS_LIB pure_quanta
J 0
(-7200 4475);
PAINT MONO (-7200 4475);
DISPLAY INVISIBLE (-7200 4475);
FORCEPROP 1 LAST PATH I49
J 0
(-7150 4625);
DISPLAY 0.978723 (-7150 4625);
PAINT WHITE (-7150 4625);
DISPLAY INVISIBLE (-7150 4625);
FORCEADD Q_CAP..1
(-8550 2875);
FORCEPROP 1 LAST LOCATION C2170
J 0
(-8500 2975);
DISPLAY 0.489362 (-8500 2975);
PAINT SKYBLUE (-8500 2975);
FORCEPROP 2 LAST $SEC 1
J 0
(-8500 3075);
DISPLAY 0.680851 (-8500 3075);
PAINT MONO (-8500 3075);
DISPLAY INVISIBLE (-8500 3075);
FORCEPROP 2 LAST CDS_SEC 1
J 0
(-8500 3075);
DISPLAY 1.021277 (-8500 3075);
DISPLAY INVISIBLE (-8500 3075);
FORCEPROP 1 LASTPIN (-8550 2975) $PN 1
J 0
(-8540 2955);
DISPLAY 0.489362 (-8540 2955);
FORCEPROP 1 LASTPIN (-8550 2775) $PN 2
J 0
(-8540 2755);
DISPLAY 0.489362 (-8540 2755);
FORCEPROP 1 LAST MATERIAL X6S
J 0
(-8500 2775);
DISPLAY 0.489362 (-8500 2775);
PAINT SKYBLUE (-8500 2775);
FORCEPROP 1 LAST TOLERANCE 20%
J 0
(-8500 2825);
DISPLAY 0.489362 (-8500 2825);
PAINT SKYBLUE (-8500 2825);
FORCEPROP 1 LAST VALUE 22UF
J 0
(-8500 2925);
DISPLAY 0.489362 (-8500 2925);
PAINT SKYBLUE (-8500 2925);
FORCEPROP 1 LAST PART_NUMBER CH622KMEB02
J 0
(-8500 2725);
DISPLAY 0.489362 (-8500 2725);
PAINT SKYBLUE (-8500 2725);
FORCEPROP 1 LAST VOLTAGE 4V
J 0
(-8500 2875);
DISPLAY 0.489362 (-8500 2875);
PAINT SKYBLUE (-8500 2875);
FORCEPROP 1 LAST PACK_TYPE C0402
J 0
(-8500 2675);
DISPLAY 0.489362 (-8500 2675);
PAINT SKYBLUE (-8500 2675);
FORCEPROP 2 LAST CDS_LIB pure_quanta
J 0
(-8550 2875);
PAINT MONO (-8550 2875);
DISPLAY INVISIBLE (-8550 2875);
FORCEPROP 1 LAST PATH I5
J 0
(-8500 3025);
DISPLAY 0.978723 (-8500 3025);
PAINT WHITE (-8500 3025);
DISPLAY INVISIBLE (-8500 3025);
FORCEADD Q_CAP..1
(-7200 5250);
FORCEPROP 1 LAST LOCATION C267
J 0
(-7150 5350);
DISPLAY 0.489362 (-7150 5350);
PAINT SKYBLUE (-7150 5350);
FORCEPROP 2 LAST $SEC 1
J 0
(-7150 5450);
DISPLAY 0.680851 (-7150 5450);
PAINT MONO (-7150 5450);
DISPLAY INVISIBLE (-7150 5450);
FORCEPROP 2 LAST CDS_SEC 1
J 0
(-7150 5450);
DISPLAY 1.021277 (-7150 5450);
DISPLAY INVISIBLE (-7150 5450);
FORCEPROP 1 LASTPIN (-7200 5350) $PN 1
J 0
(-7190 5330);
DISPLAY 0.489362 (-7190 5330);
FORCEPROP 1 LASTPIN (-7200 5150) $PN 2
J 0
(-7190 5130);
DISPLAY 0.489362 (-7190 5130);
FORCEPROP 1 LAST MATERIAL X6S
J 0
(-7150 5150);
DISPLAY 0.489362 (-7150 5150);
PAINT SKYBLUE (-7150 5150);
FORCEPROP 1 LAST TOLERANCE 20%
J 0
(-7150 5200);
DISPLAY 0.489362 (-7150 5200);
PAINT SKYBLUE (-7150 5200);
FORCEPROP 1 LAST VALUE 22UF
J 0
(-7150 5300);
DISPLAY 0.489362 (-7150 5300);
PAINT SKYBLUE (-7150 5300);
FORCEPROP 1 LAST PART_NUMBER CH622KMEB02
J 0
(-7150 5100);
DISPLAY 0.489362 (-7150 5100);
PAINT SKYBLUE (-7150 5100);
FORCEPROP 1 LAST VOLTAGE 4V
J 0
(-7150 5250);
DISPLAY 0.489362 (-7150 5250);
PAINT SKYBLUE (-7150 5250);
FORCEPROP 1 LAST PACK_TYPE C0402
J 0
(-7150 5050);
DISPLAY 0.489362 (-7150 5050);
PAINT SKYBLUE (-7150 5050);
FORCEPROP 2 LAST CDS_LIB pure_quanta
J 0
(-7200 5250);
PAINT MONO (-7200 5250);
DISPLAY INVISIBLE (-7200 5250);
FORCEPROP 1 LAST PATH I50
J 0
(-7150 5400);
DISPLAY 0.978723 (-7150 5400);
PAINT WHITE (-7150 5400);
DISPLAY INVISIBLE (-7150 5400);
FORCEADD Q_CAP..1
(-6750 4475);
FORCEPROP 1 LAST LOCATION C271
J 0
(-6700 4575);
DISPLAY 0.489362 (-6700 4575);
PAINT SKYBLUE (-6700 4575);
FORCEPROP 2 LAST $SEC 1
J 0
(-6700 4675);
DISPLAY 0.680851 (-6700 4675);
PAINT MONO (-6700 4675);
DISPLAY INVISIBLE (-6700 4675);
FORCEPROP 2 LAST CDS_SEC 1
J 0
(-6700 4675);
DISPLAY 1.021277 (-6700 4675);
DISPLAY INVISIBLE (-6700 4675);
FORCEPROP 1 LASTPIN (-6750 4575) $PN 1
J 0
(-6740 4555);
DISPLAY 0.489362 (-6740 4555);
FORCEPROP 1 LASTPIN (-6750 4375) $PN 2
J 0
(-6740 4355);
DISPLAY 0.489362 (-6740 4355);
FORCEPROP 1 LAST MATERIAL X6S
J 0
(-6700 4375);
DISPLAY 0.489362 (-6700 4375);
PAINT SKYBLUE (-6700 4375);
FORCEPROP 1 LAST TOLERANCE 20%
J 0
(-6700 4425);
DISPLAY 0.489362 (-6700 4425);
PAINT SKYBLUE (-6700 4425);
FORCEPROP 1 LAST VALUE 22UF
J 0
(-6700 4525);
DISPLAY 0.489362 (-6700 4525);
PAINT SKYBLUE (-6700 4525);
FORCEPROP 1 LAST PART_NUMBER CH622KMEB02
J 0
(-6700 4325);
DISPLAY 0.489362 (-6700 4325);
PAINT SKYBLUE (-6700 4325);
FORCEPROP 1 LAST VOLTAGE 4V
J 0
(-6700 4475);
DISPLAY 0.489362 (-6700 4475);
PAINT SKYBLUE (-6700 4475);
FORCEPROP 1 LAST PACK_TYPE C0402
J 0
(-6700 4275);
DISPLAY 0.489362 (-6700 4275);
PAINT SKYBLUE (-6700 4275);
FORCEPROP 2 LAST CDS_LIB pure_quanta
J 0
(-6750 4475);
PAINT MONO (-6750 4475);
DISPLAY INVISIBLE (-6750 4475);
FORCEPROP 1 LAST PATH I51
J 0
(-6700 4625);
DISPLAY 0.978723 (-6700 4625);
PAINT WHITE (-6700 4625);
DISPLAY INVISIBLE (-6700 4625);
FORCEADD Q_CAP..1
(-6300 4475);
FORCEPROP 1 LAST LOCATION C273
J 0
(-6250 4575);
DISPLAY 0.489362 (-6250 4575);
PAINT SKYBLUE (-6250 4575);
FORCEPROP 2 LAST $SEC 1
J 0
(-6250 4675);
DISPLAY 0.680851 (-6250 4675);
PAINT MONO (-6250 4675);
DISPLAY INVISIBLE (-6250 4675);
FORCEPROP 2 LAST CDS_SEC 1
J 0
(-6250 4675);
DISPLAY 1.021277 (-6250 4675);
DISPLAY INVISIBLE (-6250 4675);
FORCEPROP 1 LASTPIN (-6300 4575) $PN 1
J 0
(-6290 4555);
DISPLAY 0.489362 (-6290 4555);
FORCEPROP 1 LASTPIN (-6300 4375) $PN 2
J 0
(-6290 4355);
DISPLAY 0.489362 (-6290 4355);
FORCEPROP 1 LAST MATERIAL X6S
J 0
(-6250 4375);
DISPLAY 0.489362 (-6250 4375);
PAINT SKYBLUE (-6250 4375);
FORCEPROP 1 LAST TOLERANCE 20%
J 0
(-6250 4425);
DISPLAY 0.489362 (-6250 4425);
PAINT SKYBLUE (-6250 4425);
FORCEPROP 1 LAST VALUE 22UF
J 0
(-6250 4525);
DISPLAY 0.489362 (-6250 4525);
PAINT SKYBLUE (-6250 4525);
FORCEPROP 1 LAST PART_NUMBER CH622KMEB02
J 0
(-6250 4325);
DISPLAY 0.489362 (-6250 4325);
PAINT SKYBLUE (-6250 4325);
FORCEPROP 1 LAST VOLTAGE 4V
J 0
(-6250 4475);
DISPLAY 0.489362 (-6250 4475);
PAINT SKYBLUE (-6250 4475);
FORCEPROP 1 LAST PACK_TYPE C0402
J 0
(-6250 4275);
DISPLAY 0.489362 (-6250 4275);
PAINT SKYBLUE (-6250 4275);
FORCEPROP 2 LAST CDS_LIB pure_quanta
J 0
(-6300 4475);
PAINT MONO (-6300 4475);
DISPLAY INVISIBLE (-6300 4475);
FORCEPROP 1 LAST PATH I52
J 0
(-6250 4625);
DISPLAY 0.978723 (-6250 4625);
PAINT WHITE (-6250 4625);
DISPLAY INVISIBLE (-6250 4625);
FORCEADD Q_CAP..1
(-6750 5250);
FORCEPROP 1 LAST LOCATION C270
J 0
(-6700 5350);
DISPLAY 0.489362 (-6700 5350);
PAINT SKYBLUE (-6700 5350);
FORCEPROP 2 LAST $SEC 1
J 0
(-6700 5450);
DISPLAY 0.680851 (-6700 5450);
PAINT MONO (-6700 5450);
DISPLAY INVISIBLE (-6700 5450);
FORCEPROP 2 LAST CDS_SEC 1
J 0
(-6700 5450);
DISPLAY 1.021277 (-6700 5450);
DISPLAY INVISIBLE (-6700 5450);
FORCEPROP 1 LASTPIN (-6750 5350) $PN 1
J 0
(-6740 5330);
DISPLAY 0.489362 (-6740 5330);
FORCEPROP 1 LASTPIN (-6750 5150) $PN 2
J 0
(-6740 5130);
DISPLAY 0.489362 (-6740 5130);
FORCEPROP 1 LAST MATERIAL X6S
J 0
(-6700 5150);
DISPLAY 0.489362 (-6700 5150);
PAINT SKYBLUE (-6700 5150);
FORCEPROP 1 LAST TOLERANCE 20%
J 0
(-6700 5200);
DISPLAY 0.489362 (-6700 5200);
PAINT SKYBLUE (-6700 5200);
FORCEPROP 1 LAST VALUE 22UF
J 0
(-6700 5300);
DISPLAY 0.489362 (-6700 5300);
PAINT SKYBLUE (-6700 5300);
FORCEPROP 1 LAST PART_NUMBER CH622KMEB02
J 0
(-6700 5100);
DISPLAY 0.489362 (-6700 5100);
PAINT SKYBLUE (-6700 5100);
FORCEPROP 1 LAST VOLTAGE 4V
J 0
(-6700 5250);
DISPLAY 0.489362 (-6700 5250);
PAINT SKYBLUE (-6700 5250);
FORCEPROP 1 LAST PACK_TYPE C0402
J 0
(-6700 5050);
DISPLAY 0.489362 (-6700 5050);
PAINT SKYBLUE (-6700 5050);
FORCEPROP 2 LAST CDS_LIB pure_quanta
J 0
(-6750 5250);
PAINT MONO (-6750 5250);
DISPLAY INVISIBLE (-6750 5250);
FORCEPROP 1 LAST PATH I53
J 0
(-6700 5400);
DISPLAY 0.978723 (-6700 5400);
PAINT WHITE (-6700 5400);
DISPLAY INVISIBLE (-6700 5400);
FORCEADD Q_CAP..1
(-5850 4475);
FORCEPROP 1 LAST LOCATION C275
J 0
(-5800 4575);
DISPLAY 0.489362 (-5800 4575);
PAINT SKYBLUE (-5800 4575);
FORCEPROP 2 LAST $SEC 1
J 0
(-5800 4675);
DISPLAY 0.680851 (-5800 4675);
PAINT MONO (-5800 4675);
DISPLAY INVISIBLE (-5800 4675);
FORCEPROP 2 LAST CDS_SEC 1
J 0
(-5800 4675);
DISPLAY 1.021277 (-5800 4675);
DISPLAY INVISIBLE (-5800 4675);
FORCEPROP 1 LASTPIN (-5850 4575) $PN 1
J 0
(-5840 4555);
DISPLAY 0.489362 (-5840 4555);
FORCEPROP 1 LASTPIN (-5850 4375) $PN 2
J 0
(-5840 4355);
DISPLAY 0.489362 (-5840 4355);
FORCEPROP 1 LAST MATERIAL X6S
J 0
(-5800 4375);
DISPLAY 0.489362 (-5800 4375);
PAINT SKYBLUE (-5800 4375);
FORCEPROP 1 LAST TOLERANCE 20%
J 0
(-5800 4425);
DISPLAY 0.489362 (-5800 4425);
PAINT SKYBLUE (-5800 4425);
FORCEPROP 1 LAST VALUE 22UF
J 0
(-5800 4525);
DISPLAY 0.489362 (-5800 4525);
PAINT SKYBLUE (-5800 4525);
FORCEPROP 1 LAST PART_NUMBER CH622KMEB02
J 0
(-5800 4325);
DISPLAY 0.489362 (-5800 4325);
PAINT SKYBLUE (-5800 4325);
FORCEPROP 1 LAST VOLTAGE 4V
J 0
(-5800 4475);
DISPLAY 0.489362 (-5800 4475);
PAINT SKYBLUE (-5800 4475);
FORCEPROP 1 LAST PACK_TYPE C0402
J 0
(-5800 4275);
DISPLAY 0.489362 (-5800 4275);
PAINT SKYBLUE (-5800 4275);
FORCEPROP 2 LAST CDS_LIB pure_quanta
J 0
(-5850 4475);
PAINT MONO (-5850 4475);
DISPLAY INVISIBLE (-5850 4475);
FORCEPROP 1 LAST PATH I54
J 0
(-5800 4625);
DISPLAY 0.978723 (-5800 4625);
PAINT WHITE (-5800 4625);
DISPLAY INVISIBLE (-5800 4625);
FORCEADD Q_CAP..1
(-5400 4475);
FORCEPROP 1 LAST LOCATION C277
J 0
(-5350 4575);
DISPLAY 0.489362 (-5350 4575);
PAINT SKYBLUE (-5350 4575);
FORCEPROP 2 LAST $SEC 1
J 0
(-5350 4675);
DISPLAY 0.680851 (-5350 4675);
PAINT MONO (-5350 4675);
DISPLAY INVISIBLE (-5350 4675);
FORCEPROP 2 LAST CDS_SEC 1
J 0
(-5350 4675);
DISPLAY 1.021277 (-5350 4675);
DISPLAY INVISIBLE (-5350 4675);
FORCEPROP 1 LASTPIN (-5400 4575) $PN 1
J 0
(-5390 4555);
DISPLAY 0.489362 (-5390 4555);
FORCEPROP 1 LASTPIN (-5400 4375) $PN 2
J 0
(-5390 4355);
DISPLAY 0.489362 (-5390 4355);
FORCEPROP 1 LAST MATERIAL X6S
J 0
(-5350 4375);
DISPLAY 0.489362 (-5350 4375);
PAINT SKYBLUE (-5350 4375);
FORCEPROP 1 LAST TOLERANCE 20%
J 0
(-5350 4425);
DISPLAY 0.489362 (-5350 4425);
PAINT SKYBLUE (-5350 4425);
FORCEPROP 1 LAST VALUE 22UF
J 0
(-5350 4525);
DISPLAY 0.489362 (-5350 4525);
PAINT SKYBLUE (-5350 4525);
FORCEPROP 1 LAST PART_NUMBER CH622KMEB02
J 0
(-5350 4325);
DISPLAY 0.489362 (-5350 4325);
PAINT SKYBLUE (-5350 4325);
FORCEPROP 1 LAST VOLTAGE 4V
J 0
(-5350 4475);
DISPLAY 0.489362 (-5350 4475);
PAINT SKYBLUE (-5350 4475);
FORCEPROP 1 LAST PACK_TYPE C0402
J 0
(-5350 4275);
DISPLAY 0.489362 (-5350 4275);
PAINT SKYBLUE (-5350 4275);
FORCEPROP 2 LAST CDS_LIB pure_quanta
J 0
(-5400 4475);
PAINT MONO (-5400 4475);
DISPLAY INVISIBLE (-5400 4475);
FORCEPROP 1 LAST PATH I55
J 0
(-5350 4625);
DISPLAY 0.978723 (-5350 4625);
PAINT WHITE (-5350 4625);
DISPLAY INVISIBLE (-5350 4625);
FORCEADD Q_CAP..1
(-5850 5250);
FORCEPROP 1 LAST LOCATION C274
J 0
(-5800 5350);
DISPLAY 0.489362 (-5800 5350);
PAINT SKYBLUE (-5800 5350);
FORCEPROP 2 LAST $SEC 1
J 0
(-5800 5450);
DISPLAY 0.680851 (-5800 5450);
PAINT MONO (-5800 5450);
DISPLAY INVISIBLE (-5800 5450);
FORCEPROP 2 LAST CDS_SEC 1
J 0
(-5800 5450);
DISPLAY 1.021277 (-5800 5450);
DISPLAY INVISIBLE (-5800 5450);
FORCEPROP 1 LASTPIN (-5850 5350) $PN 1
J 0
(-5840 5330);
DISPLAY 0.489362 (-5840 5330);
FORCEPROP 1 LASTPIN (-5850 5150) $PN 2
J 0
(-5840 5130);
DISPLAY 0.489362 (-5840 5130);
FORCEPROP 1 LAST MATERIAL X6S
J 0
(-5800 5150);
DISPLAY 0.489362 (-5800 5150);
PAINT SKYBLUE (-5800 5150);
FORCEPROP 1 LAST TOLERANCE 20%
J 0
(-5800 5200);
DISPLAY 0.489362 (-5800 5200);
PAINT SKYBLUE (-5800 5200);
FORCEPROP 1 LAST VALUE 22UF
J 0
(-5800 5300);
DISPLAY 0.489362 (-5800 5300);
PAINT SKYBLUE (-5800 5300);
FORCEPROP 1 LAST PART_NUMBER CH622KMEB02
J 0
(-5800 5100);
DISPLAY 0.489362 (-5800 5100);
PAINT SKYBLUE (-5800 5100);
FORCEPROP 1 LAST VOLTAGE 4V
J 0
(-5800 5250);
DISPLAY 0.489362 (-5800 5250);
PAINT SKYBLUE (-5800 5250);
FORCEPROP 1 LAST PACK_TYPE C0402
J 0
(-5800 5050);
DISPLAY 0.489362 (-5800 5050);
PAINT SKYBLUE (-5800 5050);
FORCEPROP 2 LAST CDS_LIB pure_quanta
J 0
(-5850 5250);
PAINT MONO (-5850 5250);
DISPLAY INVISIBLE (-5850 5250);
FORCEPROP 1 LAST PATH I56
J 0
(-5800 5400);
DISPLAY 0.978723 (-5800 5400);
PAINT WHITE (-5800 5400);
DISPLAY INVISIBLE (-5800 5400);
FORCEADD Q_CAP..1
(-5400 5250);
FORCEPROP 1 LAST LOCATION C276
J 0
(-5350 5350);
DISPLAY 0.489362 (-5350 5350);
PAINT SKYBLUE (-5350 5350);
FORCEPROP 2 LAST $SEC 1
J 0
(-5350 5450);
DISPLAY 0.680851 (-5350 5450);
PAINT MONO (-5350 5450);
DISPLAY INVISIBLE (-5350 5450);
FORCEPROP 2 LAST CDS_SEC 1
J 0
(-5350 5450);
DISPLAY 1.021277 (-5350 5450);
DISPLAY INVISIBLE (-5350 5450);
FORCEPROP 1 LASTPIN (-5400 5350) $PN 1
J 0
(-5390 5330);
DISPLAY 0.489362 (-5390 5330);
FORCEPROP 1 LASTPIN (-5400 5150) $PN 2
J 0
(-5390 5130);
DISPLAY 0.489362 (-5390 5130);
FORCEPROP 1 LAST MATERIAL X6S
J 0
(-5350 5150);
DISPLAY 0.489362 (-5350 5150);
PAINT SKYBLUE (-5350 5150);
FORCEPROP 1 LAST TOLERANCE 20%
J 0
(-5350 5200);
DISPLAY 0.489362 (-5350 5200);
PAINT SKYBLUE (-5350 5200);
FORCEPROP 1 LAST VALUE 22UF
J 0
(-5350 5300);
DISPLAY 0.489362 (-5350 5300);
PAINT SKYBLUE (-5350 5300);
FORCEPROP 1 LAST PART_NUMBER CH622KMEB02
J 0
(-5350 5100);
DISPLAY 0.489362 (-5350 5100);
PAINT SKYBLUE (-5350 5100);
FORCEPROP 1 LAST VOLTAGE 4V
J 0
(-5350 5250);
DISPLAY 0.489362 (-5350 5250);
PAINT SKYBLUE (-5350 5250);
FORCEPROP 1 LAST PACK_TYPE C0402
J 0
(-5350 5050);
DISPLAY 0.489362 (-5350 5050);
PAINT SKYBLUE (-5350 5050);
FORCEPROP 2 LAST CDS_LIB pure_quanta
J 0
(-5400 5250);
PAINT MONO (-5400 5250);
DISPLAY INVISIBLE (-5400 5250);
FORCEPROP 1 LAST PATH I57
J 0
(-5350 5400);
DISPLAY 0.978723 (-5350 5400);
PAINT WHITE (-5350 5400);
DISPLAY INVISIBLE (-5350 5400);
FORCEADD Q_CAP..1
(-5000 4475);
FORCEPROP 1 LAST LOCATION C279
J 0
(-4950 4575);
DISPLAY 0.489362 (-4950 4575);
PAINT SKYBLUE (-4950 4575);
FORCEPROP 2 LAST $SEC 1
J 0
(-4950 4675);
DISPLAY 0.680851 (-4950 4675);
PAINT MONO (-4950 4675);
DISPLAY INVISIBLE (-4950 4675);
FORCEPROP 2 LAST CDS_SEC 1
J 0
(-4950 4675);
DISPLAY 1.021277 (-4950 4675);
DISPLAY INVISIBLE (-4950 4675);
FORCEPROP 1 LASTPIN (-5000 4575) $PN 1
J 0
(-4990 4555);
DISPLAY 0.489362 (-4990 4555);
FORCEPROP 1 LASTPIN (-5000 4375) $PN 2
J 0
(-4990 4355);
DISPLAY 0.489362 (-4990 4355);
FORCEPROP 1 LAST MATERIAL X6S
J 0
(-4950 4375);
DISPLAY 0.489362 (-4950 4375);
PAINT SKYBLUE (-4950 4375);
FORCEPROP 1 LAST TOLERANCE 20%
J 0
(-4950 4425);
DISPLAY 0.489362 (-4950 4425);
PAINT SKYBLUE (-4950 4425);
FORCEPROP 1 LAST VALUE 22UF
J 0
(-4950 4525);
DISPLAY 0.489362 (-4950 4525);
PAINT SKYBLUE (-4950 4525);
FORCEPROP 1 LAST PART_NUMBER CH622KMEB02
J 0
(-4950 4325);
DISPLAY 0.489362 (-4950 4325);
PAINT SKYBLUE (-4950 4325);
FORCEPROP 1 LAST VOLTAGE 4V
J 0
(-4950 4475);
DISPLAY 0.489362 (-4950 4475);
PAINT SKYBLUE (-4950 4475);
FORCEPROP 1 LAST PACK_TYPE C0402
J 0
(-4950 4275);
DISPLAY 0.489362 (-4950 4275);
PAINT SKYBLUE (-4950 4275);
FORCEPROP 2 LAST CDS_LIB pure_quanta
J 0
(-5000 4475);
PAINT MONO (-5000 4475);
DISPLAY INVISIBLE (-5000 4475);
FORCEPROP 1 LAST PATH I58
J 0
(-4950 4625);
DISPLAY 0.978723 (-4950 4625);
PAINT WHITE (-4950 4625);
DISPLAY INVISIBLE (-4950 4625);
FORCEADD UNIVERSAL_GND..1
(-5000 4875);
FORCEPROP 3 LASTPIN (-5000 4925) SIG_NAME GND\g
J 0
(-4990 4935);
DISPLAY 0.659574 (-4990 4935);
PAINT MONO (-4990 4935);
DISPLAY INVISIBLE (-4990 4935);
FORCEPROP 2 LAST CDS_LIB pure_quanta_power
J 0
(-5000 4875);
PAINT MONO (-5000 4875);
DISPLAY INVISIBLE (-5000 4875);
FORCEPROP 1 LAST PATH I59
J 0
(-4925 4875);
DISPLAY 0.872340 (-4925 4875);
PAINT AQUA (-4925 4875);
DISPLAY INVISIBLE (-4925 4875);
FORCEPROP 1 LAST HDL_POWER GND
J 1
(-4975 4800);
DISPLAY 0.872340 (-4975 4800);
PAINT GREEN (-4975 4800);
DISPLAY INVISIBLE (-4975 4800);
FORCEADD UNIVERSAL_POWER..1
(-9000 3150);
FORCEPROP 3 LASTPIN (-9000 3100) SIG_NAME PVDDCR_CPU0_P0\g
J 0
(-8990 3110);
DISPLAY 0.659574 (-8990 3110);
PAINT MONO (-8990 3110);
DISPLAY INVISIBLE (-8990 3110);
FORCEPROP 1 LAST HDL_POWER PVDDCR_CPU0_P0
J 1
(-9000 3200);
DISPLAY 0.489362 (-9000 3200);
PAINT GREEN (-9000 3200);
FORCEPROP 2 LAST CDS_LIB pure_quanta_power
J 0
(-9000 3150);
DISPLAY INVISIBLE (-9000 3150);
FORCEPROP 1 LAST PATH I6
J 0
(-8950 3175);
DISPLAY 0.872340 (-8950 3175);
PAINT AQUA (-8950 3175);
DISPLAY INVISIBLE (-8950 3175);
FORCEADD Q_CAP..1
(-4425 4475);
FORCEPROP 1 LAST LOCATION C2202
J 0
(-4375 4575);
DISPLAY 0.489362 (-4375 4575);
PAINT SKYBLUE (-4375 4575);
FORCEPROP 2 LAST $SEC 1
J 0
(-4375 4675);
DISPLAY 0.680851 (-4375 4675);
PAINT MONO (-4375 4675);
DISPLAY INVISIBLE (-4375 4675);
FORCEPROP 2 LAST CDS_SEC 1
J 0
(-4375 4675);
DISPLAY 1.021277 (-4375 4675);
DISPLAY INVISIBLE (-4375 4675);
FORCEPROP 1 LASTPIN (-4425 4575) $PN 1
J 0
(-4415 4555);
DISPLAY 0.489362 (-4415 4555);
FORCEPROP 1 LASTPIN (-4425 4375) $PN 2
J 0
(-4415 4355);
DISPLAY 0.489362 (-4415 4355);
FORCEPROP 1 LAST MATERIAL X6S
J 0
(-4375 4375);
DISPLAY 0.489362 (-4375 4375);
PAINT SKYBLUE (-4375 4375);
FORCEPROP 1 LAST TOLERANCE 20%
J 0
(-4375 4425);
DISPLAY 0.489362 (-4375 4425);
PAINT SKYBLUE (-4375 4425);
FORCEPROP 1 LAST VALUE 22UF
J 0
(-4375 4525);
DISPLAY 0.489362 (-4375 4525);
PAINT SKYBLUE (-4375 4525);
FORCEPROP 1 LAST PART_NUMBER CH622KMEB02
J 0
(-4375 4325);
DISPLAY 0.489362 (-4375 4325);
PAINT SKYBLUE (-4375 4325);
FORCEPROP 1 LAST VOLTAGE 4V
J 0
(-4375 4475);
DISPLAY 0.489362 (-4375 4475);
PAINT SKYBLUE (-4375 4475);
FORCEPROP 1 LAST PACK_TYPE C0402
J 0
(-4375 4275);
DISPLAY 0.489362 (-4375 4275);
PAINT SKYBLUE (-4375 4275);
FORCEPROP 2 LAST CDS_LIB pure_quanta
J 0
(-4425 4475);
PAINT MONO (-4425 4475);
DISPLAY INVISIBLE (-4425 4475);
FORCEPROP 1 LAST PATH I60
J 0
(-4375 4625);
DISPLAY 0.978723 (-4375 4625);
PAINT WHITE (-4375 4625);
DISPLAY INVISIBLE (-4375 4625);
FORCEADD UNIVERSAL_POWER..1
(-4425 4750);
FORCEPROP 3 LASTPIN (-4425 4700) SIG_NAME PVDDCR_CPU1_P0\g
J 0
(-4415 4710);
DISPLAY 0.659574 (-4415 4710);
PAINT MONO (-4415 4710);
DISPLAY INVISIBLE (-4415 4710);
FORCEPROP 1 LAST HDL_POWER PVDDCR_CPU1_P0
J 1
(-4425 4800);
DISPLAY 0.489362 (-4425 4800);
PAINT GREEN (-4425 4800);
FORCEPROP 2 LAST CDS_LIB pure_quanta_power
J 0
(-4425 4750);
DISPLAY INVISIBLE (-4425 4750);
FORCEPROP 1 LAST PATH I61
J 0
(-4375 4775);
DISPLAY 0.872340 (-4375 4775);
PAINT AQUA (-4375 4775);
DISPLAY INVISIBLE (-4375 4775);
FORCEADD Q_CAP..1
(-5000 5250);
FORCEPROP 1 LAST LOCATION C278
J 0
(-4950 5350);
DISPLAY 0.489362 (-4950 5350);
PAINT SKYBLUE (-4950 5350);
FORCEPROP 2 LAST $SEC 1
J 0
(-4950 5450);
DISPLAY 0.680851 (-4950 5450);
PAINT MONO (-4950 5450);
DISPLAY INVISIBLE (-4950 5450);
FORCEPROP 2 LAST CDS_SEC 1
J 0
(-4950 5450);
DISPLAY 1.021277 (-4950 5450);
DISPLAY INVISIBLE (-4950 5450);
FORCEPROP 1 LASTPIN (-5000 5350) $PN 1
J 0
(-4990 5330);
DISPLAY 0.489362 (-4990 5330);
FORCEPROP 1 LASTPIN (-5000 5150) $PN 2
J 0
(-4990 5130);
DISPLAY 0.489362 (-4990 5130);
FORCEPROP 1 LAST MATERIAL X6S
J 0
(-4950 5150);
DISPLAY 0.489362 (-4950 5150);
PAINT SKYBLUE (-4950 5150);
FORCEPROP 1 LAST TOLERANCE 20%
J 0
(-4950 5200);
DISPLAY 0.489362 (-4950 5200);
PAINT SKYBLUE (-4950 5200);
FORCEPROP 1 LAST VALUE 22UF
J 0
(-4950 5300);
DISPLAY 0.489362 (-4950 5300);
PAINT SKYBLUE (-4950 5300);
FORCEPROP 1 LAST PART_NUMBER CH622KMEB02
J 0
(-4950 5100);
DISPLAY 0.489362 (-4950 5100);
PAINT SKYBLUE (-4950 5100);
FORCEPROP 1 LAST VOLTAGE 4V
J 0
(-4950 5250);
DISPLAY 0.489362 (-4950 5250);
PAINT SKYBLUE (-4950 5250);
FORCEPROP 1 LAST PACK_TYPE C0402
J 0
(-4950 5050);
DISPLAY 0.489362 (-4950 5050);
PAINT SKYBLUE (-4950 5050);
FORCEPROP 2 LAST CDS_LIB pure_quanta
J 0
(-5000 5250);
PAINT MONO (-5000 5250);
DISPLAY INVISIBLE (-5000 5250);
FORCEPROP 1 LAST PATH I62
J 0
(-4950 5400);
DISPLAY 0.978723 (-4950 5400);
PAINT WHITE (-4950 5400);
DISPLAY INVISIBLE (-4950 5400);
FORCEADD Q_CAP..1
(-4425 5250);
FORCEPROP 1 LAST LOCATION C2201
J 0
(-4375 5350);
DISPLAY 0.489362 (-4375 5350);
PAINT SKYBLUE (-4375 5350);
FORCEPROP 2 LAST $SEC 1
J 0
(-4375 5450);
DISPLAY 0.680851 (-4375 5450);
PAINT MONO (-4375 5450);
DISPLAY INVISIBLE (-4375 5450);
FORCEPROP 2 LAST CDS_SEC 1
J 0
(-4375 5450);
DISPLAY 1.021277 (-4375 5450);
DISPLAY INVISIBLE (-4375 5450);
FORCEPROP 1 LASTPIN (-4425 5350) $PN 1
J 0
(-4415 5330);
DISPLAY 0.489362 (-4415 5330);
FORCEPROP 1 LASTPIN (-4425 5150) $PN 2
J 0
(-4415 5130);
DISPLAY 0.489362 (-4415 5130);
FORCEPROP 1 LAST MATERIAL X6S
J 0
(-4375 5150);
DISPLAY 0.489362 (-4375 5150);
PAINT SKYBLUE (-4375 5150);
FORCEPROP 1 LAST TOLERANCE 20%
J 0
(-4375 5200);
DISPLAY 0.489362 (-4375 5200);
PAINT SKYBLUE (-4375 5200);
FORCEPROP 1 LAST VALUE 22UF
J 0
(-4375 5300);
DISPLAY 0.489362 (-4375 5300);
PAINT SKYBLUE (-4375 5300);
FORCEPROP 1 LAST PART_NUMBER CH622KMEB02
J 0
(-4375 5100);
DISPLAY 0.489362 (-4375 5100);
PAINT SKYBLUE (-4375 5100);
FORCEPROP 1 LAST VOLTAGE 4V
J 0
(-4375 5250);
DISPLAY 0.489362 (-4375 5250);
PAINT SKYBLUE (-4375 5250);
FORCEPROP 1 LAST PACK_TYPE C0402
J 0
(-4375 5050);
DISPLAY 0.489362 (-4375 5050);
PAINT SKYBLUE (-4375 5050);
FORCEPROP 2 LAST CDS_LIB pure_quanta
J 0
(-4425 5250);
PAINT MONO (-4425 5250);
DISPLAY INVISIBLE (-4425 5250);
FORCEPROP 1 LAST PATH I63
J 0
(-4375 5400);
DISPLAY 0.978723 (-4375 5400);
PAINT WHITE (-4375 5400);
DISPLAY INVISIBLE (-4375 5400);
FORCEADD UNIVERSAL_POWER..1
(-4425 5525);
FORCEPROP 3 LASTPIN (-4425 5475) SIG_NAME PVDDCR_CPU1_P0\g
J 0
(-4415 5485);
DISPLAY 0.659574 (-4415 5485);
PAINT MONO (-4415 5485);
DISPLAY INVISIBLE (-4415 5485);
FORCEPROP 1 LAST HDL_POWER PVDDCR_CPU1_P0
J 1
(-4425 5575);
DISPLAY 0.489362 (-4425 5575);
PAINT GREEN (-4425 5575);
FORCEPROP 2 LAST CDS_LIB pure_quanta_power
J 0
(-4425 5525);
DISPLAY INVISIBLE (-4425 5525);
FORCEPROP 1 LAST PATH I64
J 0
(-4375 5550);
DISPLAY 0.872340 (-4375 5550);
PAINT AQUA (-4375 5550);
DISPLAY INVISIBLE (-4375 5550);
FORCEADD Q_CAP..1
(-3975 2075);
FORCEPROP 1 LAST LOCATION C2211
J 0
(-3925 2175);
DISPLAY 0.489362 (-3925 2175);
PAINT SKYBLUE (-3925 2175);
FORCEPROP 2 LAST $SEC 1
J 0
(-3925 2275);
DISPLAY 0.680851 (-3925 2275);
PAINT MONO (-3925 2275);
DISPLAY INVISIBLE (-3925 2275);
FORCEPROP 2 LAST CDS_SEC 1
J 0
(-3925 2275);
DISPLAY 1.021277 (-3925 2275);
DISPLAY INVISIBLE (-3925 2275);
FORCEPROP 1 LASTPIN (-3975 2175) $PN 1
J 0
(-3965 2155);
DISPLAY 0.489362 (-3965 2155);
FORCEPROP 1 LASTPIN (-3975 1975) $PN 2
J 0
(-3965 1955);
DISPLAY 0.489362 (-3965 1955);
FORCEPROP 1 LAST MATERIAL X6S
J 0
(-3925 1975);
DISPLAY 0.489362 (-3925 1975);
PAINT SKYBLUE (-3925 1975);
FORCEPROP 1 LAST TOLERANCE 20%
J 0
(-3925 2025);
DISPLAY 0.489362 (-3925 2025);
PAINT SKYBLUE (-3925 2025);
FORCEPROP 1 LAST VALUE 22UF
J 0
(-3925 2125);
DISPLAY 0.489362 (-3925 2125);
PAINT SKYBLUE (-3925 2125);
FORCEPROP 1 LAST PART_NUMBER CH622KMEB02
J 0
(-3925 1925);
DISPLAY 0.489362 (-3925 1925);
PAINT SKYBLUE (-3925 1925);
FORCEPROP 1 LAST VOLTAGE 4V
J 0
(-3925 2075);
DISPLAY 0.489362 (-3925 2075);
PAINT SKYBLUE (-3925 2075);
FORCEPROP 1 LAST PACK_TYPE C0402
J 0
(-3925 1875);
DISPLAY 0.489362 (-3925 1875);
PAINT SKYBLUE (-3925 1875);
FORCEPROP 2 LAST CDS_LIB pure_quanta
J 0
(-3975 2075);
PAINT MONO (-3975 2075);
DISPLAY INVISIBLE (-3975 2075);
FORCEPROP 1 LAST PATH I65
J 0
(-3925 2225);
DISPLAY 0.978723 (-3925 2225);
PAINT WHITE (-3925 2225);
DISPLAY INVISIBLE (-3925 2225);
FORCEADD Q_CAP..1
(-3525 2075);
FORCEPROP 1 LAST LOCATION C2217
J 0
(-3475 2175);
DISPLAY 0.489362 (-3475 2175);
PAINT SKYBLUE (-3475 2175);
FORCEPROP 2 LAST $SEC 1
J 0
(-3475 2275);
DISPLAY 0.680851 (-3475 2275);
PAINT MONO (-3475 2275);
DISPLAY INVISIBLE (-3475 2275);
FORCEPROP 2 LAST CDS_SEC 1
J 0
(-3475 2275);
DISPLAY 1.021277 (-3475 2275);
DISPLAY INVISIBLE (-3475 2275);
FORCEPROP 1 LASTPIN (-3525 2175) $PN 1
J 0
(-3515 2155);
DISPLAY 0.489362 (-3515 2155);
FORCEPROP 1 LASTPIN (-3525 1975) $PN 2
J 0
(-3515 1955);
DISPLAY 0.489362 (-3515 1955);
FORCEPROP 1 LAST MATERIAL X6S
J 0
(-3475 1975);
DISPLAY 0.489362 (-3475 1975);
PAINT SKYBLUE (-3475 1975);
FORCEPROP 1 LAST TOLERANCE 20%
J 0
(-3475 2025);
DISPLAY 0.489362 (-3475 2025);
PAINT SKYBLUE (-3475 2025);
FORCEPROP 1 LAST VALUE 22UF
J 0
(-3475 2125);
DISPLAY 0.489362 (-3475 2125);
PAINT SKYBLUE (-3475 2125);
FORCEPROP 1 LAST PART_NUMBER CH622KMEB02
J 0
(-3475 1925);
DISPLAY 0.489362 (-3475 1925);
PAINT SKYBLUE (-3475 1925);
FORCEPROP 1 LAST VOLTAGE 4V
J 0
(-3475 2075);
DISPLAY 0.489362 (-3475 2075);
PAINT SKYBLUE (-3475 2075);
FORCEPROP 1 LAST PACK_TYPE C0402
J 0
(-3475 1875);
DISPLAY 0.489362 (-3475 1875);
PAINT SKYBLUE (-3475 1875);
FORCEPROP 2 LAST CDS_LIB pure_quanta
J 0
(-3525 2075);
PAINT MONO (-3525 2075);
DISPLAY INVISIBLE (-3525 2075);
FORCEPROP 1 LAST PATH I66
J 0
(-3475 2225);
DISPLAY 0.978723 (-3475 2225);
PAINT WHITE (-3475 2225);
DISPLAY INVISIBLE (-3475 2225);
FORCEADD Q_CAP..1
(-3075 2075);
FORCEPROP 1 LAST LOCATION C2223
J 0
(-3025 2175);
DISPLAY 0.489362 (-3025 2175);
PAINT SKYBLUE (-3025 2175);
FORCEPROP 2 LAST $SEC 1
J 0
(-3025 2275);
DISPLAY 0.680851 (-3025 2275);
PAINT MONO (-3025 2275);
DISPLAY INVISIBLE (-3025 2275);
FORCEPROP 2 LAST CDS_SEC 1
J 0
(-3025 2275);
DISPLAY 1.021277 (-3025 2275);
DISPLAY INVISIBLE (-3025 2275);
FORCEPROP 1 LASTPIN (-3075 2175) $PN 1
J 0
(-3065 2155);
DISPLAY 0.489362 (-3065 2155);
FORCEPROP 1 LASTPIN (-3075 1975) $PN 2
J 0
(-3065 1955);
DISPLAY 0.489362 (-3065 1955);
FORCEPROP 1 LAST MATERIAL X6S
J 0
(-3025 1975);
DISPLAY 0.489362 (-3025 1975);
PAINT SKYBLUE (-3025 1975);
FORCEPROP 1 LAST TOLERANCE 20%
J 0
(-3025 2025);
DISPLAY 0.489362 (-3025 2025);
PAINT SKYBLUE (-3025 2025);
FORCEPROP 1 LAST VALUE 22UF
J 0
(-3025 2125);
DISPLAY 0.489362 (-3025 2125);
PAINT SKYBLUE (-3025 2125);
FORCEPROP 1 LAST PART_NUMBER CH622KMEB02
J 0
(-3025 1925);
DISPLAY 0.489362 (-3025 1925);
PAINT SKYBLUE (-3025 1925);
FORCEPROP 1 LAST VOLTAGE 4V
J 0
(-3025 2075);
DISPLAY 0.489362 (-3025 2075);
PAINT SKYBLUE (-3025 2075);
FORCEPROP 1 LAST PACK_TYPE C0402
J 0
(-3025 1875);
DISPLAY 0.489362 (-3025 1875);
PAINT SKYBLUE (-3025 1875);
FORCEPROP 2 LAST CDS_LIB pure_quanta
J 0
(-3075 2075);
PAINT MONO (-3075 2075);
DISPLAY INVISIBLE (-3075 2075);
FORCEPROP 1 LAST PATH I67
J 0
(-3025 2225);
DISPLAY 0.978723 (-3025 2225);
PAINT WHITE (-3025 2225);
DISPLAY INVISIBLE (-3025 2225);
FORCEADD UNIVERSAL_GND..1
(-2625 1725);
FORCEPROP 3 LASTPIN (-2625 1775) SIG_NAME GND\g
J 0
(-2615 1785);
DISPLAY 0.659574 (-2615 1785);
PAINT MONO (-2615 1785);
DISPLAY INVISIBLE (-2615 1785);
FORCEPROP 2 LAST CDS_LIB pure_quanta_power
J 0
(-2625 1725);
PAINT MONO (-2625 1725);
DISPLAY INVISIBLE (-2625 1725);
FORCEPROP 1 LAST PATH I68
J 0
(-2550 1725);
DISPLAY 0.872340 (-2550 1725);
PAINT AQUA (-2550 1725);
DISPLAY INVISIBLE (-2550 1725);
FORCEPROP 1 LAST HDL_POWER GND
J 1
(-2600 1650);
DISPLAY 0.872340 (-2600 1650);
PAINT GREEN (-2600 1650);
DISPLAY INVISIBLE (-2600 1650);
FORCEADD Q_CAP..1
(-2625 2075);
FORCEPROP 1 LAST LOCATION C2229
J 0
(-2575 2175);
DISPLAY 0.489362 (-2575 2175);
PAINT SKYBLUE (-2575 2175);
FORCEPROP 2 LAST $SEC 1
J 0
(-2575 2275);
DISPLAY 0.680851 (-2575 2275);
PAINT MONO (-2575 2275);
DISPLAY INVISIBLE (-2575 2275);
FORCEPROP 2 LAST CDS_SEC 1
J 0
(-2575 2275);
DISPLAY 1.021277 (-2575 2275);
DISPLAY INVISIBLE (-2575 2275);
FORCEPROP 1 LASTPIN (-2625 2175) $PN 1
J 0
(-2615 2155);
DISPLAY 0.489362 (-2615 2155);
FORCEPROP 1 LASTPIN (-2625 1975) $PN 2
J 0
(-2615 1955);
DISPLAY 0.489362 (-2615 1955);
FORCEPROP 1 LAST MATERIAL X6S
J 0
(-2575 1975);
DISPLAY 0.489362 (-2575 1975);
PAINT SKYBLUE (-2575 1975);
FORCEPROP 1 LAST TOLERANCE 20%
J 0
(-2575 2025);
DISPLAY 0.489362 (-2575 2025);
PAINT SKYBLUE (-2575 2025);
FORCEPROP 1 LAST VALUE 22UF
J 0
(-2575 2125);
DISPLAY 0.489362 (-2575 2125);
PAINT SKYBLUE (-2575 2125);
FORCEPROP 1 LAST PART_NUMBER CH622KMEB02
J 0
(-2575 1925);
DISPLAY 0.489362 (-2575 1925);
PAINT SKYBLUE (-2575 1925);
FORCEPROP 1 LAST VOLTAGE 4V
J 0
(-2575 2075);
DISPLAY 0.489362 (-2575 2075);
PAINT SKYBLUE (-2575 2075);
FORCEPROP 1 LAST PACK_TYPE C0402
J 0
(-2575 1875);
DISPLAY 0.489362 (-2575 1875);
PAINT SKYBLUE (-2575 1875);
FORCEPROP 2 LAST CDS_LIB pure_quanta
J 0
(-2625 2075);
PAINT MONO (-2625 2075);
DISPLAY INVISIBLE (-2625 2075);
FORCEPROP 1 LAST PATH I69
J 0
(-2575 2225);
DISPLAY 0.978723 (-2575 2225);
PAINT WHITE (-2575 2225);
DISPLAY INVISIBLE (-2575 2225);
FORCEADD Q_CAP..1
(-9000 3675);
FORCEPROP 1 LAST LOCATION C2165
J 0
(-8950 3775);
DISPLAY 0.489362 (-8950 3775);
PAINT SKYBLUE (-8950 3775);
FORCEPROP 2 LAST $SEC 1
J 0
(-8950 3875);
DISPLAY 0.680851 (-8950 3875);
PAINT MONO (-8950 3875);
DISPLAY INVISIBLE (-8950 3875);
FORCEPROP 2 LAST CDS_SEC 1
J 0
(-8950 3875);
DISPLAY 1.021277 (-8950 3875);
DISPLAY INVISIBLE (-8950 3875);
FORCEPROP 1 LASTPIN (-9000 3775) $PN 1
J 0
(-8990 3755);
DISPLAY 0.489362 (-8990 3755);
FORCEPROP 1 LASTPIN (-9000 3575) $PN 2
J 0
(-8990 3555);
DISPLAY 0.489362 (-8990 3555);
FORCEPROP 1 LAST MATERIAL X6S
J 0
(-8950 3575);
DISPLAY 0.489362 (-8950 3575);
PAINT SKYBLUE (-8950 3575);
FORCEPROP 1 LAST TOLERANCE 20%
J 0
(-8950 3625);
DISPLAY 0.489362 (-8950 3625);
PAINT SKYBLUE (-8950 3625);
FORCEPROP 1 LAST VALUE 22UF
J 0
(-8950 3725);
DISPLAY 0.489362 (-8950 3725);
PAINT SKYBLUE (-8950 3725);
FORCEPROP 1 LAST PART_NUMBER CH622KMEB02
J 0
(-8950 3525);
DISPLAY 0.489362 (-8950 3525);
PAINT SKYBLUE (-8950 3525);
FORCEPROP 1 LAST VOLTAGE 4V
J 0
(-8950 3675);
DISPLAY 0.489362 (-8950 3675);
PAINT SKYBLUE (-8950 3675);
FORCEPROP 1 LAST PACK_TYPE C0402
J 0
(-8950 3475);
DISPLAY 0.489362 (-8950 3475);
PAINT SKYBLUE (-8950 3475);
FORCEPROP 2 LAST CDS_LIB pure_quanta
J 0
(-9000 3675);
PAINT MONO (-9000 3675);
DISPLAY INVISIBLE (-9000 3675);
FORCEPROP 1 LAST PATH I7
J 0
(-8950 3825);
DISPLAY 0.978723 (-8950 3825);
PAINT WHITE (-8950 3825);
DISPLAY INVISIBLE (-8950 3825);
FORCEADD Q_CAP..1
(-3975 2875);
FORCEPROP 1 LAST LOCATION C2210
J 0
(-3925 2975);
DISPLAY 0.489362 (-3925 2975);
PAINT SKYBLUE (-3925 2975);
FORCEPROP 2 LAST $SEC 1
J 0
(-3925 3075);
DISPLAY 0.680851 (-3925 3075);
PAINT MONO (-3925 3075);
DISPLAY INVISIBLE (-3925 3075);
FORCEPROP 2 LAST CDS_SEC 1
J 0
(-3925 3075);
DISPLAY 1.021277 (-3925 3075);
DISPLAY INVISIBLE (-3925 3075);
FORCEPROP 1 LASTPIN (-3975 2975) $PN 1
J 0
(-3965 2955);
DISPLAY 0.489362 (-3965 2955);
FORCEPROP 1 LASTPIN (-3975 2775) $PN 2
J 0
(-3965 2755);
DISPLAY 0.489362 (-3965 2755);
FORCEPROP 1 LAST MATERIAL X6S
J 0
(-3925 2775);
DISPLAY 0.489362 (-3925 2775);
PAINT SKYBLUE (-3925 2775);
FORCEPROP 1 LAST TOLERANCE 20%
J 0
(-3925 2825);
DISPLAY 0.489362 (-3925 2825);
PAINT SKYBLUE (-3925 2825);
FORCEPROP 1 LAST VALUE 22UF
J 0
(-3925 2925);
DISPLAY 0.489362 (-3925 2925);
PAINT SKYBLUE (-3925 2925);
FORCEPROP 1 LAST PART_NUMBER CH622KMEB02
J 0
(-3925 2725);
DISPLAY 0.489362 (-3925 2725);
PAINT SKYBLUE (-3925 2725);
FORCEPROP 1 LAST VOLTAGE 4V
J 0
(-3925 2875);
DISPLAY 0.489362 (-3925 2875);
PAINT SKYBLUE (-3925 2875);
FORCEPROP 1 LAST PACK_TYPE C0402
J 0
(-3925 2675);
DISPLAY 0.489362 (-3925 2675);
PAINT SKYBLUE (-3925 2675);
FORCEPROP 2 LAST CDS_LIB pure_quanta
J 0
(-3975 2875);
PAINT MONO (-3975 2875);
DISPLAY INVISIBLE (-3975 2875);
FORCEPROP 1 LAST PATH I70
J 0
(-3925 3025);
DISPLAY 0.978723 (-3925 3025);
PAINT WHITE (-3925 3025);
DISPLAY INVISIBLE (-3925 3025);
FORCEADD Q_CAP..1
(-3525 2875);
FORCEPROP 1 LAST LOCATION C2216
J 0
(-3475 2975);
DISPLAY 0.489362 (-3475 2975);
PAINT SKYBLUE (-3475 2975);
FORCEPROP 2 LAST $SEC 1
J 0
(-3475 3075);
DISPLAY 0.680851 (-3475 3075);
PAINT MONO (-3475 3075);
DISPLAY INVISIBLE (-3475 3075);
FORCEPROP 2 LAST CDS_SEC 1
J 0
(-3475 3075);
DISPLAY 1.021277 (-3475 3075);
DISPLAY INVISIBLE (-3475 3075);
FORCEPROP 1 LASTPIN (-3525 2975) $PN 1
J 0
(-3515 2955);
DISPLAY 0.489362 (-3515 2955);
FORCEPROP 1 LASTPIN (-3525 2775) $PN 2
J 0
(-3515 2755);
DISPLAY 0.489362 (-3515 2755);
FORCEPROP 1 LAST MATERIAL X6S
J 0
(-3475 2775);
DISPLAY 0.489362 (-3475 2775);
PAINT SKYBLUE (-3475 2775);
FORCEPROP 1 LAST TOLERANCE 20%
J 0
(-3475 2825);
DISPLAY 0.489362 (-3475 2825);
PAINT SKYBLUE (-3475 2825);
FORCEPROP 1 LAST VALUE 22UF
J 0
(-3475 2925);
DISPLAY 0.489362 (-3475 2925);
PAINT SKYBLUE (-3475 2925);
FORCEPROP 1 LAST PART_NUMBER CH622KMEB02
J 0
(-3475 2725);
DISPLAY 0.489362 (-3475 2725);
PAINT SKYBLUE (-3475 2725);
FORCEPROP 1 LAST VOLTAGE 4V
J 0
(-3475 2875);
DISPLAY 0.489362 (-3475 2875);
PAINT SKYBLUE (-3475 2875);
FORCEPROP 1 LAST PACK_TYPE C0402
J 0
(-3475 2675);
DISPLAY 0.489362 (-3475 2675);
PAINT SKYBLUE (-3475 2675);
FORCEPROP 2 LAST CDS_LIB pure_quanta
J 0
(-3525 2875);
PAINT MONO (-3525 2875);
DISPLAY INVISIBLE (-3525 2875);
FORCEPROP 1 LAST PATH I71
J 0
(-3475 3025);
DISPLAY 0.978723 (-3475 3025);
PAINT WHITE (-3475 3025);
DISPLAY INVISIBLE (-3475 3025);
FORCEADD Q_CAP..1
(-3975 3675);
FORCEPROP 1 LAST LOCATION C2209
J 0
(-3925 3775);
DISPLAY 0.489362 (-3925 3775);
PAINT SKYBLUE (-3925 3775);
FORCEPROP 2 LAST $SEC 1
J 0
(-3925 3875);
DISPLAY 0.680851 (-3925 3875);
PAINT MONO (-3925 3875);
DISPLAY INVISIBLE (-3925 3875);
FORCEPROP 2 LAST CDS_SEC 1
J 0
(-3925 3875);
DISPLAY 1.021277 (-3925 3875);
DISPLAY INVISIBLE (-3925 3875);
FORCEPROP 1 LASTPIN (-3975 3775) $PN 1
J 0
(-3965 3755);
DISPLAY 0.489362 (-3965 3755);
FORCEPROP 1 LASTPIN (-3975 3575) $PN 2
J 0
(-3965 3555);
DISPLAY 0.489362 (-3965 3555);
FORCEPROP 1 LAST MATERIAL X6S
J 0
(-3925 3575);
DISPLAY 0.489362 (-3925 3575);
PAINT SKYBLUE (-3925 3575);
FORCEPROP 1 LAST TOLERANCE 20%
J 0
(-3925 3625);
DISPLAY 0.489362 (-3925 3625);
PAINT SKYBLUE (-3925 3625);
FORCEPROP 1 LAST VALUE 22UF
J 0
(-3925 3725);
DISPLAY 0.489362 (-3925 3725);
PAINT SKYBLUE (-3925 3725);
FORCEPROP 1 LAST PART_NUMBER CH622KMEB02
J 0
(-3925 3525);
DISPLAY 0.489362 (-3925 3525);
PAINT SKYBLUE (-3925 3525);
FORCEPROP 1 LAST VOLTAGE 4V
J 0
(-3925 3675);
DISPLAY 0.489362 (-3925 3675);
PAINT SKYBLUE (-3925 3675);
FORCEPROP 1 LAST PACK_TYPE C0402
J 0
(-3925 3475);
DISPLAY 0.489362 (-3925 3475);
PAINT SKYBLUE (-3925 3475);
FORCEPROP 2 LAST CDS_LIB pure_quanta
J 0
(-3975 3675);
PAINT MONO (-3975 3675);
DISPLAY INVISIBLE (-3975 3675);
FORCEPROP 1 LAST PATH I72
J 0
(-3925 3825);
DISPLAY 0.978723 (-3925 3825);
PAINT WHITE (-3925 3825);
DISPLAY INVISIBLE (-3925 3825);
FORCEADD Q_CAP..1
(-3525 3675);
FORCEPROP 1 LAST LOCATION C2215
J 0
(-3475 3775);
DISPLAY 0.489362 (-3475 3775);
PAINT SKYBLUE (-3475 3775);
FORCEPROP 2 LAST $SEC 1
J 0
(-3475 3875);
DISPLAY 0.680851 (-3475 3875);
PAINT MONO (-3475 3875);
DISPLAY INVISIBLE (-3475 3875);
FORCEPROP 2 LAST CDS_SEC 1
J 0
(-3475 3875);
DISPLAY 1.021277 (-3475 3875);
DISPLAY INVISIBLE (-3475 3875);
FORCEPROP 1 LASTPIN (-3525 3775) $PN 1
J 0
(-3515 3755);
DISPLAY 0.489362 (-3515 3755);
FORCEPROP 1 LASTPIN (-3525 3575) $PN 2
J 0
(-3515 3555);
DISPLAY 0.489362 (-3515 3555);
FORCEPROP 1 LAST MATERIAL X6S
J 0
(-3475 3575);
DISPLAY 0.489362 (-3475 3575);
PAINT SKYBLUE (-3475 3575);
FORCEPROP 1 LAST TOLERANCE 20%
J 0
(-3475 3625);
DISPLAY 0.489362 (-3475 3625);
PAINT SKYBLUE (-3475 3625);
FORCEPROP 1 LAST VALUE 22UF
J 0
(-3475 3725);
DISPLAY 0.489362 (-3475 3725);
PAINT SKYBLUE (-3475 3725);
FORCEPROP 1 LAST PART_NUMBER CH622KMEB02
J 0
(-3475 3525);
DISPLAY 0.489362 (-3475 3525);
PAINT SKYBLUE (-3475 3525);
FORCEPROP 1 LAST VOLTAGE 4V
J 0
(-3475 3675);
DISPLAY 0.489362 (-3475 3675);
PAINT SKYBLUE (-3475 3675);
FORCEPROP 1 LAST PACK_TYPE C0402
J 0
(-3475 3475);
DISPLAY 0.489362 (-3475 3475);
PAINT SKYBLUE (-3475 3475);
FORCEPROP 2 LAST CDS_LIB pure_quanta
J 0
(-3525 3675);
PAINT MONO (-3525 3675);
DISPLAY INVISIBLE (-3525 3675);
FORCEPROP 1 LAST PATH I73
J 0
(-3475 3825);
DISPLAY 0.978723 (-3475 3825);
PAINT WHITE (-3475 3825);
DISPLAY INVISIBLE (-3475 3825);
FORCEADD Q_CAP..1
(-3075 2875);
FORCEPROP 1 LAST LOCATION C2222
J 0
(-3025 2975);
DISPLAY 0.489362 (-3025 2975);
PAINT SKYBLUE (-3025 2975);
FORCEPROP 2 LAST $SEC 1
J 0
(-3025 3075);
DISPLAY 0.680851 (-3025 3075);
PAINT MONO (-3025 3075);
DISPLAY INVISIBLE (-3025 3075);
FORCEPROP 2 LAST CDS_SEC 1
J 0
(-3025 3075);
DISPLAY 1.021277 (-3025 3075);
DISPLAY INVISIBLE (-3025 3075);
FORCEPROP 1 LASTPIN (-3075 2975) $PN 1
J 0
(-3065 2955);
DISPLAY 0.489362 (-3065 2955);
FORCEPROP 1 LASTPIN (-3075 2775) $PN 2
J 0
(-3065 2755);
DISPLAY 0.489362 (-3065 2755);
FORCEPROP 1 LAST MATERIAL X6S
J 0
(-3025 2775);
DISPLAY 0.489362 (-3025 2775);
PAINT SKYBLUE (-3025 2775);
FORCEPROP 1 LAST TOLERANCE 20%
J 0
(-3025 2825);
DISPLAY 0.489362 (-3025 2825);
PAINT SKYBLUE (-3025 2825);
FORCEPROP 1 LAST VALUE 22UF
J 0
(-3025 2925);
DISPLAY 0.489362 (-3025 2925);
PAINT SKYBLUE (-3025 2925);
FORCEPROP 1 LAST PART_NUMBER CH622KMEB02
J 0
(-3025 2725);
DISPLAY 0.489362 (-3025 2725);
PAINT SKYBLUE (-3025 2725);
FORCEPROP 1 LAST VOLTAGE 4V
J 0
(-3025 2875);
DISPLAY 0.489362 (-3025 2875);
PAINT SKYBLUE (-3025 2875);
FORCEPROP 1 LAST PACK_TYPE C0402
J 0
(-3025 2675);
DISPLAY 0.489362 (-3025 2675);
PAINT SKYBLUE (-3025 2675);
FORCEPROP 2 LAST CDS_LIB pure_quanta
J 0
(-3075 2875);
PAINT MONO (-3075 2875);
DISPLAY INVISIBLE (-3075 2875);
FORCEPROP 1 LAST PATH I74
J 0
(-3025 3025);
DISPLAY 0.978723 (-3025 3025);
PAINT WHITE (-3025 3025);
DISPLAY INVISIBLE (-3025 3025);
FORCEADD Q_CAP..1
(-2625 2875);
FORCEPROP 1 LAST LOCATION C2228
J 0
(-2575 2975);
DISPLAY 0.489362 (-2575 2975);
PAINT SKYBLUE (-2575 2975);
FORCEPROP 2 LAST $SEC 1
J 0
(-2575 3075);
DISPLAY 0.680851 (-2575 3075);
PAINT MONO (-2575 3075);
DISPLAY INVISIBLE (-2575 3075);
FORCEPROP 2 LAST CDS_SEC 1
J 0
(-2575 3075);
DISPLAY 1.021277 (-2575 3075);
DISPLAY INVISIBLE (-2575 3075);
FORCEPROP 1 LASTPIN (-2625 2975) $PN 1
J 0
(-2615 2955);
DISPLAY 0.489362 (-2615 2955);
FORCEPROP 1 LASTPIN (-2625 2775) $PN 2
J 0
(-2615 2755);
DISPLAY 0.489362 (-2615 2755);
FORCEPROP 1 LAST MATERIAL X6S
J 0
(-2575 2775);
DISPLAY 0.489362 (-2575 2775);
PAINT SKYBLUE (-2575 2775);
FORCEPROP 1 LAST TOLERANCE 20%
J 0
(-2575 2825);
DISPLAY 0.489362 (-2575 2825);
PAINT SKYBLUE (-2575 2825);
FORCEPROP 1 LAST VALUE 22UF
J 0
(-2575 2925);
DISPLAY 0.489362 (-2575 2925);
PAINT SKYBLUE (-2575 2925);
FORCEPROP 1 LAST PART_NUMBER CH622KMEB02
J 0
(-2575 2725);
DISPLAY 0.489362 (-2575 2725);
PAINT SKYBLUE (-2575 2725);
FORCEPROP 1 LAST VOLTAGE 4V
J 0
(-2575 2875);
DISPLAY 0.489362 (-2575 2875);
PAINT SKYBLUE (-2575 2875);
FORCEPROP 1 LAST PACK_TYPE C0402
J 0
(-2575 2675);
DISPLAY 0.489362 (-2575 2675);
PAINT SKYBLUE (-2575 2675);
FORCEPROP 2 LAST CDS_LIB pure_quanta
J 0
(-2625 2875);
PAINT MONO (-2625 2875);
DISPLAY INVISIBLE (-2625 2875);
FORCEPROP 1 LAST PATH I75
J 0
(-2575 3025);
DISPLAY 0.978723 (-2575 3025);
PAINT WHITE (-2575 3025);
DISPLAY INVISIBLE (-2575 3025);
FORCEADD Q_CAP..1
(-2175 2875);
FORCEPROP 1 LAST LOCATION C2234
J 0
(-2125 2975);
DISPLAY 0.489362 (-2125 2975);
PAINT SKYBLUE (-2125 2975);
FORCEPROP 2 LAST $SEC 1
J 0
(-2125 3075);
DISPLAY 0.680851 (-2125 3075);
PAINT MONO (-2125 3075);
DISPLAY INVISIBLE (-2125 3075);
FORCEPROP 2 LAST CDS_SEC 1
J 0
(-2125 3075);
DISPLAY 1.021277 (-2125 3075);
DISPLAY INVISIBLE (-2125 3075);
FORCEPROP 1 LASTPIN (-2175 2975) $PN 1
J 0
(-2165 2955);
DISPLAY 0.489362 (-2165 2955);
FORCEPROP 1 LASTPIN (-2175 2775) $PN 2
J 0
(-2165 2755);
DISPLAY 0.489362 (-2165 2755);
FORCEPROP 1 LAST MATERIAL X6S
J 0
(-2125 2775);
DISPLAY 0.489362 (-2125 2775);
PAINT SKYBLUE (-2125 2775);
FORCEPROP 1 LAST TOLERANCE 20%
J 0
(-2125 2825);
DISPLAY 0.489362 (-2125 2825);
PAINT SKYBLUE (-2125 2825);
FORCEPROP 1 LAST VALUE 22UF
J 0
(-2125 2925);
DISPLAY 0.489362 (-2125 2925);
PAINT SKYBLUE (-2125 2925);
FORCEPROP 1 LAST PART_NUMBER CH622KMEB02
J 0
(-2125 2725);
DISPLAY 0.489362 (-2125 2725);
PAINT SKYBLUE (-2125 2725);
FORCEPROP 1 LAST VOLTAGE 4V
J 0
(-2125 2875);
DISPLAY 0.489362 (-2125 2875);
PAINT SKYBLUE (-2125 2875);
FORCEPROP 1 LAST PACK_TYPE C0402
J 0
(-2125 2675);
DISPLAY 0.489362 (-2125 2675);
PAINT SKYBLUE (-2125 2675);
FORCEPROP 2 LAST CDS_LIB pure_quanta
J 0
(-2175 2875);
PAINT MONO (-2175 2875);
DISPLAY INVISIBLE (-2175 2875);
FORCEPROP 1 LAST PATH I76
J 0
(-2125 3025);
DISPLAY 0.978723 (-2125 3025);
PAINT WHITE (-2125 3025);
DISPLAY INVISIBLE (-2125 3025);
FORCEADD Q_CAP..1
(-3075 3675);
FORCEPROP 1 LAST LOCATION C2221
J 0
(-3025 3775);
DISPLAY 0.489362 (-3025 3775);
PAINT SKYBLUE (-3025 3775);
FORCEPROP 2 LAST $SEC 1
J 0
(-3025 3875);
DISPLAY 0.680851 (-3025 3875);
PAINT MONO (-3025 3875);
DISPLAY INVISIBLE (-3025 3875);
FORCEPROP 2 LAST CDS_SEC 1
J 0
(-3025 3875);
DISPLAY 1.021277 (-3025 3875);
DISPLAY INVISIBLE (-3025 3875);
FORCEPROP 1 LASTPIN (-3075 3775) $PN 1
J 0
(-3065 3755);
DISPLAY 0.489362 (-3065 3755);
FORCEPROP 1 LASTPIN (-3075 3575) $PN 2
J 0
(-3065 3555);
DISPLAY 0.489362 (-3065 3555);
FORCEPROP 1 LAST MATERIAL X6S
J 0
(-3025 3575);
DISPLAY 0.489362 (-3025 3575);
PAINT SKYBLUE (-3025 3575);
FORCEPROP 1 LAST TOLERANCE 20%
J 0
(-3025 3625);
DISPLAY 0.489362 (-3025 3625);
PAINT SKYBLUE (-3025 3625);
FORCEPROP 1 LAST VALUE 22UF
J 0
(-3025 3725);
DISPLAY 0.489362 (-3025 3725);
PAINT SKYBLUE (-3025 3725);
FORCEPROP 1 LAST PART_NUMBER CH622KMEB02
J 0
(-3025 3525);
DISPLAY 0.489362 (-3025 3525);
PAINT SKYBLUE (-3025 3525);
FORCEPROP 1 LAST VOLTAGE 4V
J 0
(-3025 3675);
DISPLAY 0.489362 (-3025 3675);
PAINT SKYBLUE (-3025 3675);
FORCEPROP 1 LAST PACK_TYPE C0402
J 0
(-3025 3475);
DISPLAY 0.489362 (-3025 3475);
PAINT SKYBLUE (-3025 3475);
FORCEPROP 2 LAST CDS_LIB pure_quanta
J 0
(-3075 3675);
PAINT MONO (-3075 3675);
DISPLAY INVISIBLE (-3075 3675);
FORCEPROP 1 LAST PATH I77
J 0
(-3025 3825);
DISPLAY 0.978723 (-3025 3825);
PAINT WHITE (-3025 3825);
DISPLAY INVISIBLE (-3025 3825);
FORCEADD Q_CAP..1
(-2625 3675);
FORCEPROP 1 LAST LOCATION C2227
J 0
(-2575 3775);
DISPLAY 0.489362 (-2575 3775);
PAINT SKYBLUE (-2575 3775);
FORCEPROP 2 LAST $SEC 1
J 0
(-2575 3875);
DISPLAY 0.680851 (-2575 3875);
PAINT MONO (-2575 3875);
DISPLAY INVISIBLE (-2575 3875);
FORCEPROP 2 LAST CDS_SEC 1
J 0
(-2575 3875);
DISPLAY 1.021277 (-2575 3875);
DISPLAY INVISIBLE (-2575 3875);
FORCEPROP 1 LASTPIN (-2625 3775) $PN 1
J 0
(-2615 3755);
DISPLAY 0.489362 (-2615 3755);
FORCEPROP 1 LASTPIN (-2625 3575) $PN 2
J 0
(-2615 3555);
DISPLAY 0.489362 (-2615 3555);
FORCEPROP 1 LAST MATERIAL X6S
J 0
(-2575 3575);
DISPLAY 0.489362 (-2575 3575);
PAINT SKYBLUE (-2575 3575);
FORCEPROP 1 LAST TOLERANCE 20%
J 0
(-2575 3625);
DISPLAY 0.489362 (-2575 3625);
PAINT SKYBLUE (-2575 3625);
FORCEPROP 1 LAST VALUE 22UF
J 0
(-2575 3725);
DISPLAY 0.489362 (-2575 3725);
PAINT SKYBLUE (-2575 3725);
FORCEPROP 1 LAST PART_NUMBER CH622KMEB02
J 0
(-2575 3525);
DISPLAY 0.489362 (-2575 3525);
PAINT SKYBLUE (-2575 3525);
FORCEPROP 1 LAST VOLTAGE 4V
J 0
(-2575 3675);
DISPLAY 0.489362 (-2575 3675);
PAINT SKYBLUE (-2575 3675);
FORCEPROP 1 LAST PACK_TYPE C0402
J 0
(-2575 3475);
DISPLAY 0.489362 (-2575 3475);
PAINT SKYBLUE (-2575 3475);
FORCEPROP 2 LAST CDS_LIB pure_quanta
J 0
(-2625 3675);
PAINT MONO (-2625 3675);
DISPLAY INVISIBLE (-2625 3675);
FORCEPROP 1 LAST PATH I78
J 0
(-2575 3825);
DISPLAY 0.978723 (-2575 3825);
PAINT WHITE (-2575 3825);
DISPLAY INVISIBLE (-2575 3825);
FORCEADD Q_CAP..1
(-2175 3675);
FORCEPROP 1 LAST LOCATION C2233
J 0
(-2125 3775);
DISPLAY 0.489362 (-2125 3775);
PAINT SKYBLUE (-2125 3775);
FORCEPROP 2 LAST $SEC 1
J 0
(-2125 3875);
DISPLAY 0.680851 (-2125 3875);
PAINT MONO (-2125 3875);
DISPLAY INVISIBLE (-2125 3875);
FORCEPROP 2 LAST CDS_SEC 1
J 0
(-2125 3875);
DISPLAY 1.021277 (-2125 3875);
DISPLAY INVISIBLE (-2125 3875);
FORCEPROP 1 LASTPIN (-2175 3775) $PN 1
J 0
(-2165 3755);
DISPLAY 0.489362 (-2165 3755);
FORCEPROP 1 LASTPIN (-2175 3575) $PN 2
J 0
(-2165 3555);
DISPLAY 0.489362 (-2165 3555);
FORCEPROP 1 LAST MATERIAL X6S
J 0
(-2125 3575);
DISPLAY 0.489362 (-2125 3575);
PAINT SKYBLUE (-2125 3575);
FORCEPROP 1 LAST TOLERANCE 20%
J 0
(-2125 3625);
DISPLAY 0.489362 (-2125 3625);
PAINT SKYBLUE (-2125 3625);
FORCEPROP 1 LAST VALUE 22UF
J 0
(-2125 3725);
DISPLAY 0.489362 (-2125 3725);
PAINT SKYBLUE (-2125 3725);
FORCEPROP 1 LAST PART_NUMBER CH622KMEB02
J 0
(-2125 3525);
DISPLAY 0.489362 (-2125 3525);
PAINT SKYBLUE (-2125 3525);
FORCEPROP 1 LAST VOLTAGE 4V
J 0
(-2125 3675);
DISPLAY 0.489362 (-2125 3675);
PAINT SKYBLUE (-2125 3675);
FORCEPROP 1 LAST PACK_TYPE C0402
J 0
(-2125 3475);
DISPLAY 0.489362 (-2125 3475);
PAINT SKYBLUE (-2125 3475);
FORCEPROP 2 LAST CDS_LIB pure_quanta
J 0
(-2175 3675);
PAINT MONO (-2175 3675);
DISPLAY INVISIBLE (-2175 3675);
FORCEPROP 1 LAST PATH I79
J 0
(-2125 3825);
DISPLAY 0.978723 (-2125 3825);
PAINT WHITE (-2125 3825);
DISPLAY INVISIBLE (-2125 3825);
FORCEADD UNIVERSAL_POWER..1
(-9000 3950);
FORCEPROP 3 LASTPIN (-9000 3900) SIG_NAME PVDDCR_CPU0_P0\g
J 0
(-8990 3910);
DISPLAY 0.659574 (-8990 3910);
PAINT MONO (-8990 3910);
DISPLAY INVISIBLE (-8990 3910);
FORCEPROP 1 LAST HDL_POWER PVDDCR_CPU0_P0
J 1
(-9000 4000);
DISPLAY 0.489362 (-9000 4000);
PAINT GREEN (-9000 4000);
FORCEPROP 2 LAST CDS_LIB pure_quanta_power
J 0
(-9000 3950);
DISPLAY INVISIBLE (-9000 3950);
FORCEPROP 1 LAST PATH I8
J 0
(-8950 3975);
DISPLAY 0.872340 (-8950 3975);
PAINT AQUA (-8950 3975);
DISPLAY INVISIBLE (-8950 3975);
FORCEADD Q_CAP..1
(-1725 2875);
FORCEPROP 1 LAST LOCATION C2240
J 0
(-1675 2975);
DISPLAY 0.489362 (-1675 2975);
PAINT SKYBLUE (-1675 2975);
FORCEPROP 2 LAST $SEC 1
J 0
(-1675 3075);
DISPLAY 0.680851 (-1675 3075);
PAINT MONO (-1675 3075);
DISPLAY INVISIBLE (-1675 3075);
FORCEPROP 2 LAST CDS_SEC 1
J 0
(-1675 3075);
DISPLAY 1.021277 (-1675 3075);
DISPLAY INVISIBLE (-1675 3075);
FORCEPROP 1 LASTPIN (-1725 2975) $PN 1
J 0
(-1715 2955);
DISPLAY 0.489362 (-1715 2955);
FORCEPROP 1 LASTPIN (-1725 2775) $PN 2
J 0
(-1715 2755);
DISPLAY 0.489362 (-1715 2755);
FORCEPROP 1 LAST MATERIAL X6S
J 0
(-1675 2775);
DISPLAY 0.489362 (-1675 2775);
PAINT SKYBLUE (-1675 2775);
FORCEPROP 1 LAST TOLERANCE 20%
J 0
(-1675 2825);
DISPLAY 0.489362 (-1675 2825);
PAINT SKYBLUE (-1675 2825);
FORCEPROP 1 LAST VALUE 22UF
J 0
(-1675 2925);
DISPLAY 0.489362 (-1675 2925);
PAINT SKYBLUE (-1675 2925);
FORCEPROP 1 LAST PART_NUMBER CH622KMEB02
J 0
(-1675 2725);
DISPLAY 0.489362 (-1675 2725);
PAINT SKYBLUE (-1675 2725);
FORCEPROP 1 LAST VOLTAGE 4V
J 0
(-1675 2875);
DISPLAY 0.489362 (-1675 2875);
PAINT SKYBLUE (-1675 2875);
FORCEPROP 1 LAST PACK_TYPE C0402
J 0
(-1675 2675);
DISPLAY 0.489362 (-1675 2675);
PAINT SKYBLUE (-1675 2675);
FORCEPROP 2 LAST CDS_LIB pure_quanta
J 0
(-1725 2875);
PAINT MONO (-1725 2875);
DISPLAY INVISIBLE (-1725 2875);
FORCEPROP 1 LAST PATH I80
J 0
(-1675 3025);
DISPLAY 0.978723 (-1675 3025);
PAINT WHITE (-1675 3025);
DISPLAY INVISIBLE (-1675 3025);
FORCEADD Q_CAP..1
(-1275 2875);
FORCEPROP 1 LAST LOCATION C2246
J 0
(-1225 2975);
DISPLAY 0.489362 (-1225 2975);
PAINT SKYBLUE (-1225 2975);
FORCEPROP 2 LAST $SEC 1
J 0
(-1225 3075);
DISPLAY 0.680851 (-1225 3075);
PAINT MONO (-1225 3075);
DISPLAY INVISIBLE (-1225 3075);
FORCEPROP 2 LAST CDS_SEC 1
J 0
(-1225 3075);
DISPLAY 1.021277 (-1225 3075);
DISPLAY INVISIBLE (-1225 3075);
FORCEPROP 1 LASTPIN (-1275 2975) $PN 1
J 0
(-1265 2955);
DISPLAY 0.489362 (-1265 2955);
FORCEPROP 1 LASTPIN (-1275 2775) $PN 2
J 0
(-1265 2755);
DISPLAY 0.489362 (-1265 2755);
FORCEPROP 1 LAST MATERIAL X6S
J 0
(-1225 2775);
DISPLAY 0.489362 (-1225 2775);
PAINT SKYBLUE (-1225 2775);
FORCEPROP 1 LAST TOLERANCE 20%
J 0
(-1225 2825);
DISPLAY 0.489362 (-1225 2825);
PAINT SKYBLUE (-1225 2825);
FORCEPROP 1 LAST VALUE 22UF
J 0
(-1225 2925);
DISPLAY 0.489362 (-1225 2925);
PAINT SKYBLUE (-1225 2925);
FORCEPROP 1 LAST PART_NUMBER CH622KMEB02
J 0
(-1225 2725);
DISPLAY 0.489362 (-1225 2725);
PAINT SKYBLUE (-1225 2725);
FORCEPROP 1 LAST VOLTAGE 4V
J 0
(-1225 2875);
DISPLAY 0.489362 (-1225 2875);
PAINT SKYBLUE (-1225 2875);
FORCEPROP 1 LAST PACK_TYPE C0402
J 0
(-1225 2675);
DISPLAY 0.489362 (-1225 2675);
PAINT SKYBLUE (-1225 2675);
FORCEPROP 2 LAST CDS_LIB pure_quanta
J 0
(-1275 2875);
PAINT MONO (-1275 2875);
DISPLAY INVISIBLE (-1275 2875);
FORCEPROP 1 LAST PATH I81
J 0
(-1225 3025);
DISPLAY 0.978723 (-1225 3025);
PAINT WHITE (-1225 3025);
DISPLAY INVISIBLE (-1225 3025);
FORCEADD Q_CAP..1
(-1725 3675);
FORCEPROP 1 LAST LOCATION C2239
J 0
(-1675 3775);
DISPLAY 0.489362 (-1675 3775);
PAINT SKYBLUE (-1675 3775);
FORCEPROP 2 LAST $SEC 1
J 0
(-1675 3875);
DISPLAY 0.680851 (-1675 3875);
PAINT MONO (-1675 3875);
DISPLAY INVISIBLE (-1675 3875);
FORCEPROP 2 LAST CDS_SEC 1
J 0
(-1675 3875);
DISPLAY 1.021277 (-1675 3875);
DISPLAY INVISIBLE (-1675 3875);
FORCEPROP 1 LASTPIN (-1725 3775) $PN 1
J 0
(-1715 3755);
DISPLAY 0.489362 (-1715 3755);
FORCEPROP 1 LASTPIN (-1725 3575) $PN 2
J 0
(-1715 3555);
DISPLAY 0.489362 (-1715 3555);
FORCEPROP 1 LAST MATERIAL X6S
J 0
(-1675 3575);
DISPLAY 0.489362 (-1675 3575);
PAINT SKYBLUE (-1675 3575);
FORCEPROP 1 LAST TOLERANCE 20%
J 0
(-1675 3625);
DISPLAY 0.489362 (-1675 3625);
PAINT SKYBLUE (-1675 3625);
FORCEPROP 1 LAST VALUE 22UF
J 0
(-1675 3725);
DISPLAY 0.489362 (-1675 3725);
PAINT SKYBLUE (-1675 3725);
FORCEPROP 1 LAST PART_NUMBER CH622KMEB02
J 0
(-1675 3525);
DISPLAY 0.489362 (-1675 3525);
PAINT SKYBLUE (-1675 3525);
FORCEPROP 1 LAST VOLTAGE 4V
J 0
(-1675 3675);
DISPLAY 0.489362 (-1675 3675);
PAINT SKYBLUE (-1675 3675);
FORCEPROP 1 LAST PACK_TYPE C0402
J 0
(-1675 3475);
DISPLAY 0.489362 (-1675 3475);
PAINT SKYBLUE (-1675 3475);
FORCEPROP 2 LAST CDS_LIB pure_quanta
J 0
(-1725 3675);
PAINT MONO (-1725 3675);
DISPLAY INVISIBLE (-1725 3675);
FORCEPROP 1 LAST PATH I82
J 0
(-1675 3825);
DISPLAY 0.978723 (-1675 3825);
PAINT WHITE (-1675 3825);
DISPLAY INVISIBLE (-1675 3825);
FORCEADD Q_CAP..1
(-1275 3675);
FORCEPROP 1 LAST LOCATION C2245
J 0
(-1225 3775);
DISPLAY 0.489362 (-1225 3775);
PAINT SKYBLUE (-1225 3775);
FORCEPROP 2 LAST $SEC 1
J 0
(-1225 3875);
DISPLAY 0.680851 (-1225 3875);
PAINT MONO (-1225 3875);
DISPLAY INVISIBLE (-1225 3875);
FORCEPROP 2 LAST CDS_SEC 1
J 0
(-1225 3875);
DISPLAY 1.021277 (-1225 3875);
DISPLAY INVISIBLE (-1225 3875);
FORCEPROP 1 LASTPIN (-1275 3775) $PN 1
J 0
(-1265 3755);
DISPLAY 0.489362 (-1265 3755);
FORCEPROP 1 LASTPIN (-1275 3575) $PN 2
J 0
(-1265 3555);
DISPLAY 0.489362 (-1265 3555);
FORCEPROP 1 LAST MATERIAL X6S
J 0
(-1225 3575);
DISPLAY 0.489362 (-1225 3575);
PAINT SKYBLUE (-1225 3575);
FORCEPROP 1 LAST TOLERANCE 20%
J 0
(-1225 3625);
DISPLAY 0.489362 (-1225 3625);
PAINT SKYBLUE (-1225 3625);
FORCEPROP 1 LAST VALUE 22UF
J 0
(-1225 3725);
DISPLAY 0.489362 (-1225 3725);
PAINT SKYBLUE (-1225 3725);
FORCEPROP 1 LAST PART_NUMBER CH622KMEB02
J 0
(-1225 3525);
DISPLAY 0.489362 (-1225 3525);
PAINT SKYBLUE (-1225 3525);
FORCEPROP 1 LAST VOLTAGE 4V
J 0
(-1225 3675);
DISPLAY 0.489362 (-1225 3675);
PAINT SKYBLUE (-1225 3675);
FORCEPROP 1 LAST PACK_TYPE C0402
J 0
(-1225 3475);
DISPLAY 0.489362 (-1225 3475);
PAINT SKYBLUE (-1225 3475);
FORCEPROP 2 LAST CDS_LIB pure_quanta
J 0
(-1275 3675);
PAINT MONO (-1275 3675);
DISPLAY INVISIBLE (-1275 3675);
FORCEPROP 1 LAST PATH I83
J 0
(-1225 3825);
DISPLAY 0.978723 (-1225 3825);
PAINT WHITE (-1225 3825);
DISPLAY INVISIBLE (-1225 3825);
FORCEADD Q_CAP..1
(-825 2875);
FORCEPROP 1 LAST LOCATION C2251
J 0
(-775 2975);
DISPLAY 0.489362 (-775 2975);
PAINT SKYBLUE (-775 2975);
FORCEPROP 2 LAST $SEC 1
J 0
(-775 3075);
DISPLAY 0.680851 (-775 3075);
PAINT MONO (-775 3075);
DISPLAY INVISIBLE (-775 3075);
FORCEPROP 2 LAST CDS_SEC 1
J 0
(-775 3075);
DISPLAY 1.021277 (-775 3075);
DISPLAY INVISIBLE (-775 3075);
FORCEPROP 1 LASTPIN (-825 2975) $PN 1
J 0
(-815 2955);
DISPLAY 0.489362 (-815 2955);
FORCEPROP 1 LASTPIN (-825 2775) $PN 2
J 0
(-815 2755);
DISPLAY 0.489362 (-815 2755);
FORCEPROP 1 LAST MATERIAL X6S
J 0
(-775 2775);
DISPLAY 0.489362 (-775 2775);
PAINT SKYBLUE (-775 2775);
FORCEPROP 1 LAST TOLERANCE 20%
J 0
(-775 2825);
DISPLAY 0.489362 (-775 2825);
PAINT SKYBLUE (-775 2825);
FORCEPROP 1 LAST VALUE 22UF
J 0
(-775 2925);
DISPLAY 0.489362 (-775 2925);
PAINT SKYBLUE (-775 2925);
FORCEPROP 1 LAST PART_NUMBER CH622KMEB02
J 0
(-775 2725);
DISPLAY 0.489362 (-775 2725);
PAINT SKYBLUE (-775 2725);
FORCEPROP 1 LAST VOLTAGE 4V
J 0
(-775 2875);
DISPLAY 0.489362 (-775 2875);
PAINT SKYBLUE (-775 2875);
FORCEPROP 1 LAST PACK_TYPE C0402
J 0
(-775 2675);
DISPLAY 0.489362 (-775 2675);
PAINT SKYBLUE (-775 2675);
FORCEPROP 2 LAST CDS_LIB pure_quanta
J 0
(-825 2875);
PAINT MONO (-825 2875);
DISPLAY INVISIBLE (-825 2875);
FORCEPROP 1 LAST PATH I84
J 0
(-775 3025);
DISPLAY 0.978723 (-775 3025);
PAINT WHITE (-775 3025);
DISPLAY INVISIBLE (-775 3025);
FORCEADD UNIVERSAL_GND..1
(-425 2500);
FORCEPROP 3 LASTPIN (-425 2550) SIG_NAME GND\g
J 0
(-415 2560);
DISPLAY 0.659574 (-415 2560);
PAINT MONO (-415 2560);
DISPLAY INVISIBLE (-415 2560);
FORCEPROP 2 LAST CDS_LIB pure_quanta_power
J 0
(-425 2500);
PAINT MONO (-425 2500);
DISPLAY INVISIBLE (-425 2500);
FORCEPROP 1 LAST PATH I85
J 0
(-350 2500);
DISPLAY 0.872340 (-350 2500);
PAINT AQUA (-350 2500);
DISPLAY INVISIBLE (-350 2500);
FORCEPROP 1 LAST HDL_POWER GND
J 1
(-400 2425);
DISPLAY 0.872340 (-400 2425);
PAINT GREEN (-400 2425);
DISPLAY INVISIBLE (-400 2425);
FORCEADD Q_CAP..1
(-425 2875);
FORCEPROP 1 LAST LOCATION C2256
J 0
(-375 2975);
DISPLAY 0.489362 (-375 2975);
PAINT SKYBLUE (-375 2975);
FORCEPROP 2 LAST $SEC 1
J 0
(-375 3075);
DISPLAY 0.680851 (-375 3075);
PAINT MONO (-375 3075);
DISPLAY INVISIBLE (-375 3075);
FORCEPROP 2 LAST CDS_SEC 1
J 0
(-375 3075);
DISPLAY 1.021277 (-375 3075);
DISPLAY INVISIBLE (-375 3075);
FORCEPROP 1 LASTPIN (-425 2975) $PN 1
J 0
(-415 2955);
DISPLAY 0.489362 (-415 2955);
FORCEPROP 1 LASTPIN (-425 2775) $PN 2
J 0
(-415 2755);
DISPLAY 0.489362 (-415 2755);
FORCEPROP 1 LAST MATERIAL X6S
J 0
(-375 2775);
DISPLAY 0.489362 (-375 2775);
PAINT SKYBLUE (-375 2775);
FORCEPROP 1 LAST TOLERANCE 20%
J 0
(-375 2825);
DISPLAY 0.489362 (-375 2825);
PAINT SKYBLUE (-375 2825);
FORCEPROP 1 LAST VALUE 22UF
J 0
(-375 2925);
DISPLAY 0.489362 (-375 2925);
PAINT SKYBLUE (-375 2925);
FORCEPROP 1 LAST PART_NUMBER CH622KMEB02
J 0
(-375 2725);
DISPLAY 0.489362 (-375 2725);
PAINT SKYBLUE (-375 2725);
FORCEPROP 1 LAST VOLTAGE 4V
J 0
(-375 2875);
DISPLAY 0.489362 (-375 2875);
PAINT SKYBLUE (-375 2875);
FORCEPROP 1 LAST PACK_TYPE C0402
J 0
(-375 2675);
DISPLAY 0.489362 (-375 2675);
PAINT SKYBLUE (-375 2675);
FORCEPROP 2 LAST CDS_LIB pure_quanta
J 0
(-425 2875);
PAINT MONO (-425 2875);
DISPLAY INVISIBLE (-425 2875);
FORCEPROP 1 LAST PATH I86
J 0
(-375 3025);
DISPLAY 0.978723 (-375 3025);
PAINT WHITE (-375 3025);
DISPLAY INVISIBLE (-375 3025);
FORCEADD Q_CAP..1
(-825 3675);
FORCEPROP 1 LAST LOCATION C2250
J 0
(-775 3775);
DISPLAY 0.489362 (-775 3775);
PAINT SKYBLUE (-775 3775);
FORCEPROP 2 LAST $SEC 1
J 0
(-775 3875);
DISPLAY 0.680851 (-775 3875);
PAINT MONO (-775 3875);
DISPLAY INVISIBLE (-775 3875);
FORCEPROP 2 LAST CDS_SEC 1
J 0
(-775 3875);
DISPLAY 1.021277 (-775 3875);
DISPLAY INVISIBLE (-775 3875);
FORCEPROP 1 LASTPIN (-825 3775) $PN 1
J 0
(-815 3755);
DISPLAY 0.489362 (-815 3755);
FORCEPROP 1 LASTPIN (-825 3575) $PN 2
J 0
(-815 3555);
DISPLAY 0.489362 (-815 3555);
FORCEPROP 1 LAST MATERIAL X6S
J 0
(-775 3575);
DISPLAY 0.489362 (-775 3575);
PAINT SKYBLUE (-775 3575);
FORCEPROP 1 LAST TOLERANCE 20%
J 0
(-775 3625);
DISPLAY 0.489362 (-775 3625);
PAINT SKYBLUE (-775 3625);
FORCEPROP 1 LAST VALUE 22UF
J 0
(-775 3725);
DISPLAY 0.489362 (-775 3725);
PAINT SKYBLUE (-775 3725);
FORCEPROP 1 LAST PART_NUMBER CH622KMEB02
J 0
(-775 3525);
DISPLAY 0.489362 (-775 3525);
PAINT SKYBLUE (-775 3525);
FORCEPROP 1 LAST VOLTAGE 4V
J 0
(-775 3675);
DISPLAY 0.489362 (-775 3675);
PAINT SKYBLUE (-775 3675);
FORCEPROP 1 LAST PACK_TYPE C0402
J 0
(-775 3475);
DISPLAY 0.489362 (-775 3475);
PAINT SKYBLUE (-775 3475);
FORCEPROP 2 LAST CDS_LIB pure_quanta
J 0
(-825 3675);
PAINT MONO (-825 3675);
DISPLAY INVISIBLE (-825 3675);
FORCEPROP 1 LAST PATH I87
J 0
(-775 3825);
DISPLAY 0.978723 (-775 3825);
PAINT WHITE (-775 3825);
DISPLAY INVISIBLE (-775 3825);
FORCEADD UNIVERSAL_GND..1
(-425 3300);
FORCEPROP 3 LASTPIN (-425 3350) SIG_NAME GND\g
J 0
(-415 3360);
DISPLAY 0.659574 (-415 3360);
PAINT MONO (-415 3360);
DISPLAY INVISIBLE (-415 3360);
FORCEPROP 2 LAST CDS_LIB pure_quanta_power
J 0
(-425 3300);
PAINT MONO (-425 3300);
DISPLAY INVISIBLE (-425 3300);
FORCEPROP 1 LAST PATH I88
J 0
(-350 3300);
DISPLAY 0.872340 (-350 3300);
PAINT AQUA (-350 3300);
DISPLAY INVISIBLE (-350 3300);
FORCEPROP 1 LAST HDL_POWER GND
J 1
(-400 3225);
DISPLAY 0.872340 (-400 3225);
PAINT GREEN (-400 3225);
DISPLAY INVISIBLE (-400 3225);
FORCEADD Q_CAP..1
(-425 3675);
FORCEPROP 1 LAST LOCATION C2255
J 0
(-375 3775);
DISPLAY 0.489362 (-375 3775);
PAINT SKYBLUE (-375 3775);
FORCEPROP 2 LAST $SEC 1
J 0
(-375 3875);
DISPLAY 0.680851 (-375 3875);
PAINT MONO (-375 3875);
DISPLAY INVISIBLE (-375 3875);
FORCEPROP 2 LAST CDS_SEC 1
J 0
(-375 3875);
DISPLAY 1.021277 (-375 3875);
DISPLAY INVISIBLE (-375 3875);
FORCEPROP 1 LASTPIN (-425 3775) $PN 1
J 0
(-415 3755);
DISPLAY 0.489362 (-415 3755);
FORCEPROP 1 LASTPIN (-425 3575) $PN 2
J 0
(-415 3555);
DISPLAY 0.489362 (-415 3555);
FORCEPROP 1 LAST MATERIAL X6S
J 0
(-375 3575);
DISPLAY 0.489362 (-375 3575);
PAINT SKYBLUE (-375 3575);
FORCEPROP 1 LAST TOLERANCE 20%
J 0
(-375 3625);
DISPLAY 0.489362 (-375 3625);
PAINT SKYBLUE (-375 3625);
FORCEPROP 1 LAST VALUE 22UF
J 0
(-375 3725);
DISPLAY 0.489362 (-375 3725);
PAINT SKYBLUE (-375 3725);
FORCEPROP 1 LAST PART_NUMBER CH622KMEB02
J 0
(-375 3525);
DISPLAY 0.489362 (-375 3525);
PAINT SKYBLUE (-375 3525);
FORCEPROP 1 LAST VOLTAGE 4V
J 0
(-375 3675);
DISPLAY 0.489362 (-375 3675);
PAINT SKYBLUE (-375 3675);
FORCEPROP 1 LAST PACK_TYPE C0402
J 0
(-375 3475);
DISPLAY 0.489362 (-375 3475);
PAINT SKYBLUE (-375 3475);
FORCEPROP 2 LAST CDS_LIB pure_quanta
J 0
(-425 3675);
PAINT MONO (-425 3675);
DISPLAY INVISIBLE (-425 3675);
FORCEPROP 1 LAST PATH I89
J 0
(-375 3825);
DISPLAY 0.978723 (-375 3825);
PAINT WHITE (-375 3825);
DISPLAY INVISIBLE (-375 3825);
FORCEADD Q_CAP..1
(-8550 3675);
FORCEPROP 1 LAST LOCATION C2169
J 0
(-8500 3775);
DISPLAY 0.489362 (-8500 3775);
PAINT SKYBLUE (-8500 3775);
FORCEPROP 2 LAST $SEC 1
J 0
(-8500 3875);
DISPLAY 0.680851 (-8500 3875);
PAINT MONO (-8500 3875);
DISPLAY INVISIBLE (-8500 3875);
FORCEPROP 2 LAST CDS_SEC 1
J 0
(-8500 3875);
DISPLAY 1.021277 (-8500 3875);
DISPLAY INVISIBLE (-8500 3875);
FORCEPROP 1 LASTPIN (-8550 3775) $PN 1
J 0
(-8540 3755);
DISPLAY 0.489362 (-8540 3755);
FORCEPROP 1 LASTPIN (-8550 3575) $PN 2
J 0
(-8540 3555);
DISPLAY 0.489362 (-8540 3555);
FORCEPROP 1 LAST MATERIAL X6S
J 0
(-8500 3575);
DISPLAY 0.489362 (-8500 3575);
PAINT SKYBLUE (-8500 3575);
FORCEPROP 1 LAST TOLERANCE 20%
J 0
(-8500 3625);
DISPLAY 0.489362 (-8500 3625);
PAINT SKYBLUE (-8500 3625);
FORCEPROP 1 LAST VALUE 22UF
J 0
(-8500 3725);
DISPLAY 0.489362 (-8500 3725);
PAINT SKYBLUE (-8500 3725);
FORCEPROP 1 LAST PART_NUMBER CH622KMEB02
J 0
(-8500 3525);
DISPLAY 0.489362 (-8500 3525);
PAINT SKYBLUE (-8500 3525);
FORCEPROP 1 LAST VOLTAGE 4V
J 0
(-8500 3675);
DISPLAY 0.489362 (-8500 3675);
PAINT SKYBLUE (-8500 3675);
FORCEPROP 1 LAST PACK_TYPE C0402
J 0
(-8500 3475);
DISPLAY 0.489362 (-8500 3475);
PAINT SKYBLUE (-8500 3475);
FORCEPROP 2 LAST CDS_LIB pure_quanta
J 0
(-8550 3675);
PAINT MONO (-8550 3675);
DISPLAY INVISIBLE (-8550 3675);
FORCEPROP 1 LAST PATH I9
J 0
(-8500 3825);
DISPLAY 0.978723 (-8500 3825);
PAINT WHITE (-8500 3825);
DISPLAY INVISIBLE (-8500 3825);
FORCEADD UNIVERSAL_GND..1
(-425 4100);
FORCEPROP 3 LASTPIN (-425 4150) SIG_NAME GND\g
J 0
(-415 4160);
DISPLAY 0.659574 (-415 4160);
PAINT MONO (-415 4160);
DISPLAY INVISIBLE (-415 4160);
FORCEPROP 2 LAST CDS_LIB pure_quanta_power
J 0
(-425 4100);
PAINT MONO (-425 4100);
DISPLAY INVISIBLE (-425 4100);
FORCEPROP 1 LAST PATH I90
J 0
(-350 4100);
DISPLAY 0.872340 (-350 4100);
PAINT AQUA (-350 4100);
DISPLAY INVISIBLE (-350 4100);
FORCEPROP 1 LAST HDL_POWER GND
J 1
(-400 4025);
DISPLAY 0.872340 (-400 4025);
PAINT GREEN (-400 4025);
DISPLAY INVISIBLE (-400 4025);
FORCEADD Q_CAP..1
(-3975 4475);
FORCEPROP 1 LAST LOCATION C2208
J 0
(-3925 4575);
DISPLAY 0.489362 (-3925 4575);
PAINT SKYBLUE (-3925 4575);
FORCEPROP 2 LAST $SEC 1
J 0
(-3925 4675);
DISPLAY 0.680851 (-3925 4675);
PAINT MONO (-3925 4675);
DISPLAY INVISIBLE (-3925 4675);
FORCEPROP 2 LAST CDS_SEC 1
J 0
(-3925 4675);
DISPLAY 1.021277 (-3925 4675);
DISPLAY INVISIBLE (-3925 4675);
FORCEPROP 1 LASTPIN (-3975 4575) $PN 1
J 0
(-3965 4555);
DISPLAY 0.489362 (-3965 4555);
FORCEPROP 1 LASTPIN (-3975 4375) $PN 2
J 0
(-3965 4355);
DISPLAY 0.489362 (-3965 4355);
FORCEPROP 1 LAST MATERIAL X6S
J 0
(-3925 4375);
DISPLAY 0.489362 (-3925 4375);
PAINT SKYBLUE (-3925 4375);
FORCEPROP 1 LAST TOLERANCE 20%
J 0
(-3925 4425);
DISPLAY 0.489362 (-3925 4425);
PAINT SKYBLUE (-3925 4425);
FORCEPROP 1 LAST VALUE 22UF
J 0
(-3925 4525);
DISPLAY 0.489362 (-3925 4525);
PAINT SKYBLUE (-3925 4525);
FORCEPROP 1 LAST PART_NUMBER CH622KMEB02
J 0
(-3925 4325);
DISPLAY 0.489362 (-3925 4325);
PAINT SKYBLUE (-3925 4325);
FORCEPROP 1 LAST VOLTAGE 4V
J 0
(-3925 4475);
DISPLAY 0.489362 (-3925 4475);
PAINT SKYBLUE (-3925 4475);
FORCEPROP 1 LAST PACK_TYPE C0402
J 0
(-3925 4275);
DISPLAY 0.489362 (-3925 4275);
PAINT SKYBLUE (-3925 4275);
FORCEPROP 2 LAST CDS_LIB pure_quanta
J 0
(-3975 4475);
PAINT MONO (-3975 4475);
DISPLAY INVISIBLE (-3975 4475);
FORCEPROP 1 LAST PATH I91
J 0
(-3925 4625);
DISPLAY 0.978723 (-3925 4625);
PAINT WHITE (-3925 4625);
DISPLAY INVISIBLE (-3925 4625);
FORCEADD Q_CAP..1
(-3525 4475);
FORCEPROP 1 LAST LOCATION C2214
J 0
(-3475 4575);
DISPLAY 0.489362 (-3475 4575);
PAINT SKYBLUE (-3475 4575);
FORCEPROP 2 LAST $SEC 1
J 0
(-3475 4675);
DISPLAY 0.680851 (-3475 4675);
PAINT MONO (-3475 4675);
DISPLAY INVISIBLE (-3475 4675);
FORCEPROP 2 LAST CDS_SEC 1
J 0
(-3475 4675);
DISPLAY 1.021277 (-3475 4675);
DISPLAY INVISIBLE (-3475 4675);
FORCEPROP 1 LASTPIN (-3525 4575) $PN 1
J 0
(-3515 4555);
DISPLAY 0.489362 (-3515 4555);
FORCEPROP 1 LASTPIN (-3525 4375) $PN 2
J 0
(-3515 4355);
DISPLAY 0.489362 (-3515 4355);
FORCEPROP 1 LAST MATERIAL X6S
J 0
(-3475 4375);
DISPLAY 0.489362 (-3475 4375);
PAINT SKYBLUE (-3475 4375);
FORCEPROP 1 LAST TOLERANCE 20%
J 0
(-3475 4425);
DISPLAY 0.489362 (-3475 4425);
PAINT SKYBLUE (-3475 4425);
FORCEPROP 1 LAST VALUE 22UF
J 0
(-3475 4525);
DISPLAY 0.489362 (-3475 4525);
PAINT SKYBLUE (-3475 4525);
FORCEPROP 1 LAST PART_NUMBER CH622KMEB02
J 0
(-3475 4325);
DISPLAY 0.489362 (-3475 4325);
PAINT SKYBLUE (-3475 4325);
FORCEPROP 1 LAST VOLTAGE 4V
J 0
(-3475 4475);
DISPLAY 0.489362 (-3475 4475);
PAINT SKYBLUE (-3475 4475);
FORCEPROP 1 LAST PACK_TYPE C0402
J 0
(-3475 4275);
DISPLAY 0.489362 (-3475 4275);
PAINT SKYBLUE (-3475 4275);
FORCEPROP 2 LAST CDS_LIB pure_quanta
J 0
(-3525 4475);
PAINT MONO (-3525 4475);
DISPLAY INVISIBLE (-3525 4475);
FORCEPROP 1 LAST PATH I92
J 0
(-3475 4625);
DISPLAY 0.978723 (-3475 4625);
PAINT WHITE (-3475 4625);
DISPLAY INVISIBLE (-3475 4625);
FORCEADD Q_CAP..1
(-3975 5250);
FORCEPROP 1 LAST LOCATION C2207
J 0
(-3925 5350);
DISPLAY 0.489362 (-3925 5350);
PAINT SKYBLUE (-3925 5350);
FORCEPROP 2 LAST $SEC 1
J 0
(-3925 5450);
DISPLAY 0.680851 (-3925 5450);
PAINT MONO (-3925 5450);
DISPLAY INVISIBLE (-3925 5450);
FORCEPROP 2 LAST CDS_SEC 1
J 0
(-3925 5450);
DISPLAY 1.021277 (-3925 5450);
DISPLAY INVISIBLE (-3925 5450);
FORCEPROP 1 LASTPIN (-3975 5350) $PN 1
J 0
(-3965 5330);
DISPLAY 0.489362 (-3965 5330);
FORCEPROP 1 LASTPIN (-3975 5150) $PN 2
J 0
(-3965 5130);
DISPLAY 0.489362 (-3965 5130);
FORCEPROP 1 LAST MATERIAL X6S
J 0
(-3925 5150);
DISPLAY 0.489362 (-3925 5150);
PAINT SKYBLUE (-3925 5150);
FORCEPROP 1 LAST TOLERANCE 20%
J 0
(-3925 5200);
DISPLAY 0.489362 (-3925 5200);
PAINT SKYBLUE (-3925 5200);
FORCEPROP 1 LAST VALUE 22UF
J 0
(-3925 5300);
DISPLAY 0.489362 (-3925 5300);
PAINT SKYBLUE (-3925 5300);
FORCEPROP 1 LAST PART_NUMBER CH622KMEB02
J 0
(-3925 5100);
DISPLAY 0.489362 (-3925 5100);
PAINT SKYBLUE (-3925 5100);
FORCEPROP 1 LAST VOLTAGE 4V
J 0
(-3925 5250);
DISPLAY 0.489362 (-3925 5250);
PAINT SKYBLUE (-3925 5250);
FORCEPROP 1 LAST PACK_TYPE C0402
J 0
(-3925 5050);
DISPLAY 0.489362 (-3925 5050);
PAINT SKYBLUE (-3925 5050);
FORCEPROP 2 LAST CDS_LIB pure_quanta
J 0
(-3975 5250);
PAINT MONO (-3975 5250);
DISPLAY INVISIBLE (-3975 5250);
FORCEPROP 1 LAST PATH I93
J 0
(-3925 5400);
DISPLAY 0.978723 (-3925 5400);
PAINT WHITE (-3925 5400);
DISPLAY INVISIBLE (-3925 5400);
FORCEADD Q_CAP..1
(-3525 5250);
FORCEPROP 1 LAST LOCATION C2213
J 0
(-3475 5350);
DISPLAY 0.489362 (-3475 5350);
PAINT SKYBLUE (-3475 5350);
FORCEPROP 2 LAST $SEC 1
J 0
(-3475 5450);
DISPLAY 0.680851 (-3475 5450);
PAINT MONO (-3475 5450);
DISPLAY INVISIBLE (-3475 5450);
FORCEPROP 2 LAST CDS_SEC 1
J 0
(-3475 5450);
DISPLAY 1.021277 (-3475 5450);
DISPLAY INVISIBLE (-3475 5450);
FORCEPROP 1 LASTPIN (-3525 5350) $PN 1
J 0
(-3515 5330);
DISPLAY 0.489362 (-3515 5330);
FORCEPROP 1 LASTPIN (-3525 5150) $PN 2
J 0
(-3515 5130);
DISPLAY 0.489362 (-3515 5130);
FORCEPROP 1 LAST MATERIAL X6S
J 0
(-3475 5150);
DISPLAY 0.489362 (-3475 5150);
PAINT SKYBLUE (-3475 5150);
FORCEPROP 1 LAST TOLERANCE 20%
J 0
(-3475 5200);
DISPLAY 0.489362 (-3475 5200);
PAINT SKYBLUE (-3475 5200);
FORCEPROP 1 LAST VALUE 22UF
J 0
(-3475 5300);
DISPLAY 0.489362 (-3475 5300);
PAINT SKYBLUE (-3475 5300);
FORCEPROP 1 LAST PART_NUMBER CH622KMEB02
J 0
(-3475 5100);
DISPLAY 0.489362 (-3475 5100);
PAINT SKYBLUE (-3475 5100);
FORCEPROP 1 LAST VOLTAGE 4V
J 0
(-3475 5250);
DISPLAY 0.489362 (-3475 5250);
PAINT SKYBLUE (-3475 5250);
FORCEPROP 1 LAST PACK_TYPE C0402
J 0
(-3475 5050);
DISPLAY 0.489362 (-3475 5050);
PAINT SKYBLUE (-3475 5050);
FORCEPROP 2 LAST CDS_LIB pure_quanta
J 0
(-3525 5250);
PAINT MONO (-3525 5250);
DISPLAY INVISIBLE (-3525 5250);
FORCEPROP 1 LAST PATH I94
J 0
(-3475 5400);
DISPLAY 0.978723 (-3475 5400);
PAINT WHITE (-3475 5400);
DISPLAY INVISIBLE (-3475 5400);
FORCEADD Q_CAP..1
(-3075 4475);
FORCEPROP 1 LAST LOCATION C2220
J 0
(-3025 4575);
DISPLAY 0.489362 (-3025 4575);
PAINT SKYBLUE (-3025 4575);
FORCEPROP 2 LAST $SEC 1
J 0
(-3025 4675);
DISPLAY 0.680851 (-3025 4675);
PAINT MONO (-3025 4675);
DISPLAY INVISIBLE (-3025 4675);
FORCEPROP 2 LAST CDS_SEC 1
J 0
(-3025 4675);
DISPLAY 1.021277 (-3025 4675);
DISPLAY INVISIBLE (-3025 4675);
FORCEPROP 1 LASTPIN (-3075 4575) $PN 1
J 0
(-3065 4555);
DISPLAY 0.489362 (-3065 4555);
FORCEPROP 1 LASTPIN (-3075 4375) $PN 2
J 0
(-3065 4355);
DISPLAY 0.489362 (-3065 4355);
FORCEPROP 1 LAST MATERIAL X6S
J 0
(-3025 4375);
DISPLAY 0.489362 (-3025 4375);
PAINT SKYBLUE (-3025 4375);
FORCEPROP 1 LAST TOLERANCE 20%
J 0
(-3025 4425);
DISPLAY 0.489362 (-3025 4425);
PAINT SKYBLUE (-3025 4425);
FORCEPROP 1 LAST VALUE 22UF
J 0
(-3025 4525);
DISPLAY 0.489362 (-3025 4525);
PAINT SKYBLUE (-3025 4525);
FORCEPROP 1 LAST PART_NUMBER CH622KMEB02
J 0
(-3025 4325);
DISPLAY 0.489362 (-3025 4325);
PAINT SKYBLUE (-3025 4325);
FORCEPROP 1 LAST VOLTAGE 4V
J 0
(-3025 4475);
DISPLAY 0.489362 (-3025 4475);
PAINT SKYBLUE (-3025 4475);
FORCEPROP 1 LAST PACK_TYPE C0402
J 0
(-3025 4275);
DISPLAY 0.489362 (-3025 4275);
PAINT SKYBLUE (-3025 4275);
FORCEPROP 2 LAST CDS_LIB pure_quanta
J 0
(-3075 4475);
PAINT MONO (-3075 4475);
DISPLAY INVISIBLE (-3075 4475);
FORCEPROP 1 LAST PATH I95
J 0
(-3025 4625);
DISPLAY 0.978723 (-3025 4625);
PAINT WHITE (-3025 4625);
DISPLAY INVISIBLE (-3025 4625);
FORCEADD Q_CAP..1
(-2625 4475);
FORCEPROP 1 LAST LOCATION C2226
J 0
(-2575 4575);
DISPLAY 0.489362 (-2575 4575);
PAINT SKYBLUE (-2575 4575);
FORCEPROP 2 LAST $SEC 1
J 0
(-2575 4675);
DISPLAY 0.680851 (-2575 4675);
PAINT MONO (-2575 4675);
DISPLAY INVISIBLE (-2575 4675);
FORCEPROP 2 LAST CDS_SEC 1
J 0
(-2575 4675);
DISPLAY 1.021277 (-2575 4675);
DISPLAY INVISIBLE (-2575 4675);
FORCEPROP 1 LASTPIN (-2625 4575) $PN 1
J 0
(-2615 4555);
DISPLAY 0.489362 (-2615 4555);
FORCEPROP 1 LASTPIN (-2625 4375) $PN 2
J 0
(-2615 4355);
DISPLAY 0.489362 (-2615 4355);
FORCEPROP 1 LAST MATERIAL X6S
J 0
(-2575 4375);
DISPLAY 0.489362 (-2575 4375);
PAINT SKYBLUE (-2575 4375);
FORCEPROP 1 LAST TOLERANCE 20%
J 0
(-2575 4425);
DISPLAY 0.489362 (-2575 4425);
PAINT SKYBLUE (-2575 4425);
FORCEPROP 1 LAST VALUE 22UF
J 0
(-2575 4525);
DISPLAY 0.489362 (-2575 4525);
PAINT SKYBLUE (-2575 4525);
FORCEPROP 1 LAST PART_NUMBER CH622KMEB02
J 0
(-2575 4325);
DISPLAY 0.489362 (-2575 4325);
PAINT SKYBLUE (-2575 4325);
FORCEPROP 1 LAST VOLTAGE 4V
J 0
(-2575 4475);
DISPLAY 0.489362 (-2575 4475);
PAINT SKYBLUE (-2575 4475);
FORCEPROP 1 LAST PACK_TYPE C0402
J 0
(-2575 4275);
DISPLAY 0.489362 (-2575 4275);
PAINT SKYBLUE (-2575 4275);
FORCEPROP 2 LAST CDS_LIB pure_quanta
J 0
(-2625 4475);
PAINT MONO (-2625 4475);
DISPLAY INVISIBLE (-2625 4475);
FORCEPROP 1 LAST PATH I96
J 0
(-2575 4625);
DISPLAY 0.978723 (-2575 4625);
PAINT WHITE (-2575 4625);
DISPLAY INVISIBLE (-2575 4625);
FORCEADD Q_CAP..1
(-2175 4475);
FORCEPROP 1 LAST LOCATION C2232
J 0
(-2125 4575);
DISPLAY 0.489362 (-2125 4575);
PAINT SKYBLUE (-2125 4575);
FORCEPROP 2 LAST $SEC 1
J 0
(-2125 4675);
DISPLAY 0.680851 (-2125 4675);
PAINT MONO (-2125 4675);
DISPLAY INVISIBLE (-2125 4675);
FORCEPROP 2 LAST CDS_SEC 1
J 0
(-2125 4675);
DISPLAY 1.021277 (-2125 4675);
DISPLAY INVISIBLE (-2125 4675);
FORCEPROP 1 LASTPIN (-2175 4575) $PN 1
J 0
(-2165 4555);
DISPLAY 0.489362 (-2165 4555);
FORCEPROP 1 LASTPIN (-2175 4375) $PN 2
J 0
(-2165 4355);
DISPLAY 0.489362 (-2165 4355);
FORCEPROP 1 LAST MATERIAL X6S
J 0
(-2125 4375);
DISPLAY 0.489362 (-2125 4375);
PAINT SKYBLUE (-2125 4375);
FORCEPROP 1 LAST TOLERANCE 20%
J 0
(-2125 4425);
DISPLAY 0.489362 (-2125 4425);
PAINT SKYBLUE (-2125 4425);
FORCEPROP 1 LAST VALUE 22UF
J 0
(-2125 4525);
DISPLAY 0.489362 (-2125 4525);
PAINT SKYBLUE (-2125 4525);
FORCEPROP 1 LAST PART_NUMBER CH622KMEB02
J 0
(-2125 4325);
DISPLAY 0.489362 (-2125 4325);
PAINT SKYBLUE (-2125 4325);
FORCEPROP 1 LAST VOLTAGE 4V
J 0
(-2125 4475);
DISPLAY 0.489362 (-2125 4475);
PAINT SKYBLUE (-2125 4475);
FORCEPROP 1 LAST PACK_TYPE C0402
J 0
(-2125 4275);
DISPLAY 0.489362 (-2125 4275);
PAINT SKYBLUE (-2125 4275);
FORCEPROP 2 LAST CDS_LIB pure_quanta
J 0
(-2175 4475);
PAINT MONO (-2175 4475);
DISPLAY INVISIBLE (-2175 4475);
FORCEPROP 1 LAST PATH I97
J 0
(-2125 4625);
DISPLAY 0.978723 (-2125 4625);
PAINT WHITE (-2125 4625);
DISPLAY INVISIBLE (-2125 4625);
FORCEADD Q_CAP..1
(-3075 5250);
FORCEPROP 1 LAST LOCATION C2219
J 0
(-3025 5350);
DISPLAY 0.489362 (-3025 5350);
PAINT SKYBLUE (-3025 5350);
FORCEPROP 2 LAST $SEC 1
J 0
(-3025 5450);
DISPLAY 0.680851 (-3025 5450);
PAINT MONO (-3025 5450);
DISPLAY INVISIBLE (-3025 5450);
FORCEPROP 2 LAST CDS_SEC 1
J 0
(-3025 5450);
DISPLAY 1.021277 (-3025 5450);
DISPLAY INVISIBLE (-3025 5450);
FORCEPROP 1 LASTPIN (-3075 5350) $PN 1
J 0
(-3065 5330);
DISPLAY 0.489362 (-3065 5330);
FORCEPROP 1 LASTPIN (-3075 5150) $PN 2
J 0
(-3065 5130);
DISPLAY 0.489362 (-3065 5130);
FORCEPROP 1 LAST MATERIAL X6S
J 0
(-3025 5150);
DISPLAY 0.489362 (-3025 5150);
PAINT SKYBLUE (-3025 5150);
FORCEPROP 1 LAST TOLERANCE 20%
J 0
(-3025 5200);
DISPLAY 0.489362 (-3025 5200);
PAINT SKYBLUE (-3025 5200);
FORCEPROP 1 LAST VALUE 22UF
J 0
(-3025 5300);
DISPLAY 0.489362 (-3025 5300);
PAINT SKYBLUE (-3025 5300);
FORCEPROP 1 LAST PART_NUMBER CH622KMEB02
J 0
(-3025 5100);
DISPLAY 0.489362 (-3025 5100);
PAINT SKYBLUE (-3025 5100);
FORCEPROP 1 LAST VOLTAGE 4V
J 0
(-3025 5250);
DISPLAY 0.489362 (-3025 5250);
PAINT SKYBLUE (-3025 5250);
FORCEPROP 1 LAST PACK_TYPE C0402
J 0
(-3025 5050);
DISPLAY 0.489362 (-3025 5050);
PAINT SKYBLUE (-3025 5050);
FORCEPROP 2 LAST CDS_LIB pure_quanta
J 0
(-3075 5250);
PAINT MONO (-3075 5250);
DISPLAY INVISIBLE (-3075 5250);
FORCEPROP 1 LAST PATH I98
J 0
(-3025 5400);
DISPLAY 0.978723 (-3025 5400);
PAINT WHITE (-3025 5400);
DISPLAY INVISIBLE (-3025 5400);
FORCEADD Q_CAP..1
(-2625 5250);
FORCEPROP 1 LAST LOCATION C2225
J 0
(-2575 5350);
DISPLAY 0.489362 (-2575 5350);
PAINT SKYBLUE (-2575 5350);
FORCEPROP 2 LAST $SEC 1
J 0
(-2575 5450);
DISPLAY 0.680851 (-2575 5450);
PAINT MONO (-2575 5450);
DISPLAY INVISIBLE (-2575 5450);
FORCEPROP 2 LAST CDS_SEC 1
J 0
(-2575 5450);
DISPLAY 1.021277 (-2575 5450);
DISPLAY INVISIBLE (-2575 5450);
FORCEPROP 1 LASTPIN (-2625 5350) $PN 1
J 0
(-2615 5330);
DISPLAY 0.489362 (-2615 5330);
FORCEPROP 1 LASTPIN (-2625 5150) $PN 2
J 0
(-2615 5130);
DISPLAY 0.489362 (-2615 5130);
FORCEPROP 1 LAST MATERIAL X6S
J 0
(-2575 5150);
DISPLAY 0.489362 (-2575 5150);
PAINT SKYBLUE (-2575 5150);
FORCEPROP 1 LAST TOLERANCE 20%
J 0
(-2575 5200);
DISPLAY 0.489362 (-2575 5200);
PAINT SKYBLUE (-2575 5200);
FORCEPROP 1 LAST VALUE 22UF
J 0
(-2575 5300);
DISPLAY 0.489362 (-2575 5300);
PAINT SKYBLUE (-2575 5300);
FORCEPROP 1 LAST PART_NUMBER CH622KMEB02
J 0
(-2575 5100);
DISPLAY 0.489362 (-2575 5100);
PAINT SKYBLUE (-2575 5100);
FORCEPROP 1 LAST VOLTAGE 4V
J 0
(-2575 5250);
DISPLAY 0.489362 (-2575 5250);
PAINT SKYBLUE (-2575 5250);
FORCEPROP 1 LAST PACK_TYPE C0402
J 0
(-2575 5050);
DISPLAY 0.489362 (-2575 5050);
PAINT SKYBLUE (-2575 5050);
FORCEPROP 2 LAST CDS_LIB pure_quanta
J 0
(-2625 5250);
PAINT MONO (-2625 5250);
DISPLAY INVISIBLE (-2625 5250);
FORCEPROP 1 LAST PATH I99
J 0
(-2575 5400);
DISPLAY 0.978723 (-2575 5400);
PAINT WHITE (-2575 5400);
DISPLAY INVISIBLE (-2575 5400);
FORCEADD QUANTA_TITLE_BLOCK_C..1
(25 -225);
FORCEPROP 0 LAST CDS_CON_LAST_MODIFIED Fri Mar 11 14:52:44 2022
J 0
(-1860 -210);
DISPLAY INVISIBLE (-1860 -210);
FORCEPROP 1 LAST CUSTOM_TXT_CDS <CON_LAST_MODIFIED>
J 0
(-1860 -210);
DISPLAY 0.978723 (-1860 -210);
FORCEPROP 2 LAST CUSTOM_TXT_CDS <XR_PAGE_TITLE>
J 0
(-7865 5025);
DISPLAY 0.638298 (-7865 5025);
PAINT PINK (-7865 5025);
DISPLAY INVISIBLE (-7865 5025);
FORCEPROP 1 LAST CUSTOM_TXT_CDS <NAME_2>
J 0
(-3150 -175);
FORCEPROP 1 LAST CUSTOM_TXT_CDS <NAME_1>
J 0
(-3150 -50);
FORCEPROP 1 LAST CUSTOM_TXT_CDS <Q_NUMBER>
J 0
(-1378 -122);
DISPLAY 1.212766 (-1378 -122);
FORCEPROP 1 LAST CUSTOM_TXT_CDS <Q_PROJ>
J 0
(-2357 -123);
DISPLAY 1.212766 (-2357 -123);
FORCEPROP 1 LAST CUSTOM_TXT_CDS <Q_REV>
J 0
(-159 -122);
DISPLAY 1.212766 (-159 -122);
FORCEPROP 1 LAST CUSTOM_TXT_CDS <CON_PAGE_NUM> OF <CON_TOTAL_PAGES>
J 0
(-421 -207);
DISPLAY 0.978723 (-421 -207);
FORCEPROP 1 LAST Q_DEPT BU9
J 1
(-3738 -176);
DISPLAY 1.957447 (-3738 -176);
PAINT GREEN (-3738 -176);
FORCEPROP 1 LAST Q_TITLE CPU0 CAVITY BOT DECOUPLING CAPS 1/3
J 0
(-9341 -199);
DISPLAY 2.446809 (-9341 -199);
PAINT GREEN (-9341 -199);
FORCEPROP 2 LAST PAGE_BORDER TRUE
J 0
(-7865 5025);
DISPLAY 0.638298 (-7865 5025);
PAINT PINK (-7865 5025);
DISPLAY INVISIBLE (-7865 5025);
FORCEPROP 1 LAST CDS_LMAN_SYM_OUTLINE -9475,6775,100,-125
J 0
(25 -225);
DISPLAY 0.468085 (25 -225);
PAINT GREEN (25 -225);
DISPLAY INVISIBLE (25 -225);
FORCEPROP 2 LAST CDS_LIB pure_quanta
J 0
(25 -225);
DISPLAY INVISIBLE (25 -225);
FORCEPROP 1 LAST COMMENT_BODY TRUE
J 0
(37 -238);
DISPLAY 0.978723 (37 -238);
PAINT GREEN (37 -238);
DISPLAY INVISIBLE (37 -238);
FORCEPROP 2 LAST CDS_XR_PAGE_TITLE CR-68 : @T6G_MB_LIB.T6G(SCH_1):PAGE68
J 0
(-7865 5025);
DISPLAY 0.638298 (-7865 5025);
PAINT PINK (-7865 5025);
DISPLAY INVISIBLE (-7865 5025);
WIRE 16 -1 (-8550 1850)(-9000 1850);
WIRE 16 -1 (-8100 1850)(-8550 1850);
WIRE 16 -1 (-8550 1850)(-8550 1975);
WIRE 16 -1 (-9000 1850)(-9000 1975);
WIRE 16 -1 (-7650 1850)(-8100 1850);
WIRE 16 -1 (-8100 1850)(-8100 1975);
WIRE 16 -1 (-7200 1850)(-7650 1850);
WIRE 16 -1 (-7650 1850)(-7650 1975);
WIRE 16 -1 (-7200 1850)(-7200 1975);
WIRE 16 -1 (-7200 1725)(-7200 1850);
WIRE 16 -1 (-8550 2650)(-9000 2650);
WIRE 16 -1 (-8100 2650)(-8550 2650);
WIRE 16 -1 (-8550 2650)(-8550 2775);
WIRE 16 -1 (-9000 2650)(-9000 2775);
WIRE 16 -1 (-7650 2650)(-8100 2650);
WIRE 16 -1 (-8100 2650)(-8100 2775);
WIRE 16 -1 (-7200 2650)(-7650 2650);
WIRE 16 -1 (-7650 2650)(-7650 2775);
WIRE 16 -1 (-6750 2650)(-7200 2650);
WIRE 16 -1 (-7200 2650)(-7200 2775);
WIRE 16 -1 (-6300 2650)(-6750 2650);
WIRE 16 -1 (-6750 2650)(-6750 2775);
WIRE 16 -1 (-5850 2650)(-6300 2650);
WIRE 16 -1 (-6300 2650)(-6300 2775);
WIRE 16 -1 (-5400 2650)(-5850 2650);
WIRE 16 -1 (-5850 2650)(-5850 2775);
WIRE 16 -1 (-5400 2650)(-5000 2650);
WIRE 16 -1 (-5400 2650)(-5400 2775);
WIRE 16 -1 (-5000 2650)(-5000 2775);
WIRE 16 -1 (-5000 2550)(-5000 2650);
WIRE 16 -1 (-8550 2250)(-9000 2250);
WIRE 16 -1 (-8100 2250)(-8550 2250);
WIRE 16 -1 (-8550 2175)(-8550 2250);
WIRE 16 -1 (-9000 2250)(-9000 2300);
WIRE 16 -1 (-9000 2250)(-9000 2175);
WIRE 16 -1 (-7650 2250)(-8100 2250);
WIRE 16 -1 (-8100 2250)(-8100 2175);
WIRE 16 -1 (-7200 2250)(-7650 2250);
WIRE 16 -1 (-7650 2175)(-7650 2250);
WIRE 16 -1 (-7200 2175)(-7200 2250);
WIRE 16 -1 (-5000 2975)(-5000 3050);
WIRE 16 -1 (-5000 3050)(-5400 3050);
WIRE 16 -1 (-5400 3050)(-5400 2975);
WIRE 16 -1 (-5400 3050)(-5850 3050);
WIRE 16 -1 (-5850 2975)(-5850 3050);
WIRE 16 -1 (-5850 3050)(-6300 3050);
WIRE 16 -1 (-6300 2975)(-6300 3050);
WIRE 16 -1 (-6300 3050)(-6750 3050);
WIRE 16 -1 (-6750 3050)(-6750 2975);
WIRE 16 -1 (-6750 3050)(-7200 3050);
WIRE 16 -1 (-7200 2975)(-7200 3050);
WIRE 16 -1 (-7200 3050)(-7650 3050);
WIRE 16 -1 (-7650 2975)(-7650 3050);
WIRE 16 -1 (-7650 3050)(-8100 3050);
WIRE 16 -1 (-8100 3050)(-8100 2975);
WIRE 16 -1 (-8100 3050)(-8550 3050);
WIRE 16 -1 (-8550 3050)(-9000 3050);
WIRE 16 -1 (-8550 2975)(-8550 3050);
WIRE 16 -1 (-9000 3050)(-9000 3100);
WIRE 16 -1 (-9000 3050)(-9000 2975);
WIRE 16 -1 (-5000 3775)(-5000 3850);
WIRE 16 -1 (-5000 3850)(-5400 3850);
WIRE 16 -1 (-5400 3850)(-5400 3775);
WIRE 16 -1 (-5400 3850)(-5850 3850);
WIRE 16 -1 (-5850 3775)(-5850 3850);
WIRE 16 -1 (-5850 3850)(-6300 3850);
WIRE 16 -1 (-6300 3775)(-6300 3850);
WIRE 16 -1 (-6300 3850)(-6750 3850);
WIRE 16 -1 (-6750 3850)(-6750 3775);
WIRE 16 -1 (-6750 3850)(-7200 3850);
WIRE 16 -1 (-7200 3775)(-7200 3850);
WIRE 16 -1 (-7200 3850)(-7650 3850);
WIRE 16 -1 (-7650 3775)(-7650 3850);
WIRE 16 -1 (-7650 3850)(-8100 3850);
WIRE 16 -1 (-8100 3850)(-8100 3775);
WIRE 16 -1 (-8100 3850)(-8550 3850);
WIRE 16 -1 (-8550 3850)(-9000 3850);
WIRE 16 -1 (-8550 3775)(-8550 3850);
WIRE 16 -1 (-9000 3850)(-9000 3900);
WIRE 16 -1 (-9000 3850)(-9000 3775);
WIRE 16 -1 (-8550 3450)(-9000 3450);
WIRE 16 -1 (-8100 3450)(-8550 3450);
WIRE 16 -1 (-8550 3450)(-8550 3575);
WIRE 16 -1 (-9000 3450)(-9000 3575);
WIRE 16 -1 (-7650 3450)(-8100 3450);
WIRE 16 -1 (-8100 3450)(-8100 3575);
WIRE 16 -1 (-7200 3450)(-7650 3450);
WIRE 16 -1 (-7650 3450)(-7650 3575);
WIRE 16 -1 (-6750 3450)(-7200 3450);
WIRE 16 -1 (-7200 3450)(-7200 3575);
WIRE 16 -1 (-6300 3450)(-6750 3450);
WIRE 16 -1 (-6750 3450)(-6750 3575);
WIRE 16 -1 (-5850 3450)(-6300 3450);
WIRE 16 -1 (-6300 3450)(-6300 3575);
WIRE 16 -1 (-5400 3450)(-5850 3450);
WIRE 16 -1 (-5850 3450)(-5850 3575);
WIRE 16 -1 (-5400 3450)(-5000 3450);
WIRE 16 -1 (-5400 3450)(-5400 3575);
WIRE 16 -1 (-5000 3350)(-5000 3450);
WIRE 16 -1 (-5000 3450)(-5000 3575);
WIRE 16 -1 (-5000 4575)(-5000 4650);
WIRE 16 -1 (-5000 4650)(-5400 4650);
WIRE 16 -1 (-5400 4650)(-5400 4575);
WIRE 16 -1 (-5400 4650)(-5850 4650);
WIRE 16 -1 (-5850 4575)(-5850 4650);
WIRE 16 -1 (-5850 4650)(-6300 4650);
WIRE 16 -1 (-6300 4575)(-6300 4650);
WIRE 16 -1 (-6300 4650)(-6750 4650);
WIRE 16 -1 (-6750 4650)(-6750 4575);
WIRE 16 -1 (-6750 4650)(-7200 4650);
WIRE 16 -1 (-7200 4575)(-7200 4650);
WIRE 16 -1 (-7200 4650)(-7650 4650);
WIRE 16 -1 (-7650 4575)(-7650 4650);
WIRE 16 -1 (-7650 4650)(-8100 4650);
WIRE 16 -1 (-8100 4650)(-8100 4575);
WIRE 16 -1 (-8100 4650)(-8550 4650);
WIRE 16 -1 (-8550 4650)(-9000 4650);
WIRE 16 -1 (-8550 4575)(-8550 4650);
WIRE 16 -1 (-9000 4650)(-9000 4700);
WIRE 16 -1 (-9000 4650)(-9000 4575);
WIRE 16 -1 (-8550 4250)(-9000 4250);
WIRE 16 -1 (-8100 4250)(-8550 4250);
WIRE 16 -1 (-8550 4250)(-8550 4375);
WIRE 16 -1 (-9000 4250)(-9000 4375);
WIRE 16 -1 (-7650 4250)(-8100 4250);
WIRE 16 -1 (-8100 4250)(-8100 4375);
WIRE 16 -1 (-7200 4250)(-7650 4250);
WIRE 16 -1 (-7650 4250)(-7650 4375);
WIRE 16 -1 (-6750 4250)(-7200 4250);
WIRE 16 -1 (-7200 4250)(-7200 4375);
WIRE 16 -1 (-6300 4250)(-6750 4250);
WIRE 16 -1 (-6750 4250)(-6750 4375);
WIRE 16 -1 (-5850 4250)(-6300 4250);
WIRE 16 -1 (-6300 4250)(-6300 4375);
WIRE 16 -1 (-5400 4250)(-5850 4250);
WIRE 16 -1 (-5850 4250)(-5850 4375);
WIRE 16 -1 (-5400 4250)(-5000 4250);
WIRE 16 -1 (-5400 4250)(-5400 4375);
WIRE 16 -1 (-5000 4250)(-5000 4375);
WIRE 16 -1 (-5000 4150)(-5000 4250);
WIRE 16 -1 (-9000 5025)(-9000 5150);
WIRE 16 -1 (-8550 5025)(-9000 5025);
WIRE 16 -1 (-8100 5025)(-8550 5025);
WIRE 16 -1 (-8550 5025)(-8550 5150);
WIRE 16 -1 (-8100 5025)(-8100 5150);
WIRE 16 -1 (-7650 5025)(-8100 5025);
WIRE 16 -1 (-7650 5025)(-7650 5150);
WIRE 16 -1 (-7200 5025)(-7650 5025);
WIRE 16 -1 (-6750 5025)(-7200 5025);
WIRE 16 -1 (-7200 5025)(-7200 5150);
WIRE 16 -1 (-6750 5025)(-6750 5150);
WIRE 16 -1 (-6300 5025)(-6750 5025);
WIRE 16 -1 (-5850 5025)(-6300 5025);
WIRE 16 -1 (-6300 5025)(-6300 5150);
WIRE 16 -1 (-5850 5025)(-5850 5150);
WIRE 16 -1 (-5400 5025)(-5850 5025);
WIRE 16 -1 (-5000 5025)(-5400 5025);
WIRE 16 -1 (-5400 5025)(-5400 5150);
WIRE 16 -1 (-5000 5025)(-5000 5150);
WIRE 16 -1 (-5000 4925)(-5000 5025);
WIRE 16 -1 (-5000 5350)(-5000 5425);
WIRE 16 -1 (-5000 5425)(-5400 5425);
WIRE 16 -1 (-5400 5425)(-5400 5350);
WIRE 16 -1 (-5400 5425)(-5850 5425);
WIRE 16 -1 (-5850 5350)(-5850 5425);
WIRE 16 -1 (-5850 5425)(-6300 5425);
WIRE 16 -1 (-6300 5350)(-6300 5425);
WIRE 16 -1 (-6300 5425)(-6750 5425);
WIRE 16 -1 (-6750 5425)(-6750 5350);
WIRE 16 -1 (-6750 5425)(-7200 5425);
WIRE 16 -1 (-7200 5350)(-7200 5425);
WIRE 16 -1 (-7200 5425)(-7650 5425);
WIRE 16 -1 (-7650 5350)(-7650 5425);
WIRE 16 -1 (-7650 5425)(-8100 5425);
WIRE 16 -1 (-8100 5425)(-8100 5350);
WIRE 16 -1 (-8100 5425)(-8550 5425);
WIRE 16 -1 (-8550 5425)(-9000 5425);
WIRE 16 -1 (-8550 5350)(-8550 5425);
WIRE 16 -1 (-9000 5425)(-9000 5475);
WIRE 16 -1 (-9000 5425)(-9000 5350);
WIRE 16 3135 (-9200 800)(-9150 800);
WIRE 16 3135 (-9150 800)(-4700 800);
WIRE 16 3135 (-9150 800)(-9150 6100);
WIRE 16 3135 (-9200 6100)(-9150 6100);
WIRE 16 3135 (-9150 6100)(-4700 6100);
WIRE 16 3135 (-4700 800)(-4700 6100);
WIRE 16 -1 (-425 5350)(-425 5425);
WIRE 16 -1 (-425 5425)(-825 5425);
WIRE 16 -1 (-825 5425)(-825 5350);
WIRE 16 -1 (-825 5425)(-1275 5425);
WIRE 16 -1 (-1275 5350)(-1275 5425);
WIRE 16 -1 (-1275 5425)(-1725 5425);
WIRE 16 -1 (-1725 5350)(-1725 5425);
WIRE 16 -1 (-1725 5425)(-2175 5425);
WIRE 16 -1 (-2175 5425)(-2175 5350);
WIRE 16 -1 (-2175 5425)(-2625 5425);
WIRE 16 -1 (-2625 5350)(-2625 5425);
WIRE 16 -1 (-2625 5425)(-3075 5425);
WIRE 16 -1 (-3075 5350)(-3075 5425);
WIRE 16 -1 (-3075 5425)(-3525 5425);
WIRE 16 -1 (-3525 5425)(-3525 5350);
WIRE 16 -1 (-3525 5425)(-3975 5425);
WIRE 16 -1 (-3975 5425)(-4425 5425);
WIRE 16 -1 (-3975 5350)(-3975 5425);
WIRE 16 -1 (-4425 5425)(-4425 5475);
WIRE 16 -1 (-4425 5425)(-4425 5350);
WIRE 16 -1 (-3975 5025)(-4425 5025);
WIRE 16 -1 (-3975 5025)(-3975 5150);
WIRE 16 -1 (-3525 5025)(-3975 5025);
WIRE 16 -1 (-4425 5025)(-4425 5150);
WIRE 16 -1 (-3525 5025)(-3525 5150);
WIRE 16 -1 (-3075 5025)(-3525 5025);
WIRE 16 -1 (-2625 5025)(-3075 5025);
WIRE 16 -1 (-3075 5025)(-3075 5150);
WIRE 16 -1 (-2625 5025)(-2625 5150);
WIRE 16 -1 (-2175 5025)(-2625 5025);
WIRE 16 -1 (-1725 5025)(-2175 5025);
WIRE 16 -1 (-2175 5025)(-2175 5150);
WIRE 16 -1 (-1725 5025)(-1725 5150);
WIRE 16 -1 (-1275 5025)(-1725 5025);
WIRE 16 -1 (-825 5025)(-1275 5025);
WIRE 16 -1 (-1275 5025)(-1275 5150);
WIRE 16 -1 (-825 5025)(-825 5150);
WIRE 16 -1 (-425 5025)(-825 5025);
WIRE 16 -1 (-425 5025)(-425 5150);
WIRE 16 -1 (-425 4925)(-425 5025);
WIRE 16 -1 (-425 4575)(-425 4650);
WIRE 16 -1 (-425 4650)(-825 4650);
WIRE 16 -1 (-825 4650)(-825 4575);
WIRE 16 -1 (-825 4650)(-1275 4650);
WIRE 16 -1 (-1275 4575)(-1275 4650);
WIRE 16 -1 (-1275 4650)(-1725 4650);
WIRE 16 -1 (-1725 4575)(-1725 4650);
WIRE 16 -1 (-1725 4650)(-2175 4650);
WIRE 16 -1 (-2175 4650)(-2175 4575);
WIRE 16 -1 (-2175 4650)(-2625 4650);
WIRE 16 -1 (-2625 4575)(-2625 4650);
WIRE 16 -1 (-2625 4650)(-3075 4650);
WIRE 16 -1 (-3075 4575)(-3075 4650);
WIRE 16 -1 (-3075 4650)(-3525 4650);
WIRE 16 -1 (-3525 4650)(-3525 4575);
WIRE 16 -1 (-3525 4650)(-3975 4650);
WIRE 16 -1 (-3975 4650)(-4425 4650);
WIRE 16 -1 (-3975 4575)(-3975 4650);
WIRE 16 -1 (-4425 4650)(-4425 4700);
WIRE 16 -1 (-4425 4650)(-4425 4575);
WIRE 16 -1 (-3975 4250)(-4425 4250);
WIRE 16 -1 (-3525 4250)(-3975 4250);
WIRE 16 -1 (-3975 4250)(-3975 4375);
WIRE 16 -1 (-4425 4250)(-4425 4375);
WIRE 16 -1 (-3075 4250)(-3525 4250);
WIRE 16 -1 (-3525 4250)(-3525 4375);
WIRE 16 -1 (-2625 4250)(-3075 4250);
WIRE 16 -1 (-3075 4250)(-3075 4375);
WIRE 16 -1 (-2175 4250)(-2625 4250);
WIRE 16 -1 (-2625 4250)(-2625 4375);
WIRE 16 -1 (-1725 4250)(-2175 4250);
WIRE 16 -1 (-2175 4250)(-2175 4375);
WIRE 16 -1 (-1275 4250)(-1725 4250);
WIRE 16 -1 (-1725 4250)(-1725 4375);
WIRE 16 -1 (-825 4250)(-1275 4250);
WIRE 16 -1 (-1275 4250)(-1275 4375);
WIRE 16 -1 (-825 4250)(-425 4250);
WIRE 16 -1 (-825 4250)(-825 4375);
WIRE 16 -1 (-425 4250)(-425 4375);
WIRE 16 -1 (-425 4150)(-425 4250);
WIRE 16 -1 (-425 3775)(-425 3850);
WIRE 16 -1 (-425 3850)(-825 3850);
WIRE 16 -1 (-825 3850)(-825 3775);
WIRE 16 -1 (-825 3850)(-1275 3850);
WIRE 16 -1 (-1275 3775)(-1275 3850);
WIRE 16 -1 (-1275 3850)(-1725 3850);
WIRE 16 -1 (-1725 3775)(-1725 3850);
WIRE 16 -1 (-1725 3850)(-2175 3850);
WIRE 16 -1 (-2175 3850)(-2175 3775);
WIRE 16 -1 (-2175 3850)(-2625 3850);
WIRE 16 -1 (-2625 3775)(-2625 3850);
WIRE 16 -1 (-2625 3850)(-3075 3850);
WIRE 16 -1 (-3075 3775)(-3075 3850);
WIRE 16 -1 (-3075 3850)(-3525 3850);
WIRE 16 -1 (-3525 3850)(-3525 3775);
WIRE 16 -1 (-3525 3850)(-3975 3850);
WIRE 16 -1 (-3975 3850)(-4425 3850);
WIRE 16 -1 (-3975 3775)(-3975 3850);
WIRE 16 -1 (-4425 3850)(-4425 3900);
WIRE 16 -1 (-4425 3850)(-4425 3775);
WIRE 16 -1 (-3975 3450)(-4425 3450);
WIRE 16 -1 (-3525 3450)(-3975 3450);
WIRE 16 -1 (-3975 3450)(-3975 3575);
WIRE 16 -1 (-4425 3450)(-4425 3575);
WIRE 16 -1 (-3075 3450)(-3525 3450);
WIRE 16 -1 (-3525 3450)(-3525 3575);
WIRE 16 -1 (-2625 3450)(-3075 3450);
WIRE 16 -1 (-3075 3450)(-3075 3575);
WIRE 16 -1 (-2175 3450)(-2625 3450);
WIRE 16 -1 (-2625 3450)(-2625 3575);
WIRE 16 -1 (-1725 3450)(-2175 3450);
WIRE 16 -1 (-2175 3450)(-2175 3575);
WIRE 16 -1 (-1275 3450)(-1725 3450);
WIRE 16 -1 (-1725 3450)(-1725 3575);
WIRE 16 -1 (-825 3450)(-1275 3450);
WIRE 16 -1 (-1275 3450)(-1275 3575);
WIRE 16 -1 (-825 3450)(-425 3450);
WIRE 16 -1 (-825 3450)(-825 3575);
WIRE 16 -1 (-425 3350)(-425 3450);
WIRE 16 -1 (-425 3450)(-425 3575);
WIRE 16 -1 (-425 2975)(-425 3050);
WIRE 16 -1 (-425 3050)(-825 3050);
WIRE 16 -1 (-825 3050)(-825 2975);
WIRE 16 -1 (-825 3050)(-1275 3050);
WIRE 16 -1 (-1275 2975)(-1275 3050);
WIRE 16 -1 (-1275 3050)(-1725 3050);
WIRE 16 -1 (-1725 2975)(-1725 3050);
WIRE 16 -1 (-1725 3050)(-2175 3050);
WIRE 16 -1 (-2175 3050)(-2175 2975);
WIRE 16 -1 (-2175 3050)(-2625 3050);
WIRE 16 -1 (-2625 2975)(-2625 3050);
WIRE 16 -1 (-2625 3050)(-3075 3050);
WIRE 16 -1 (-3075 2975)(-3075 3050);
WIRE 16 -1 (-3075 3050)(-3525 3050);
WIRE 16 -1 (-3525 3050)(-3525 2975);
WIRE 16 -1 (-3525 3050)(-3975 3050);
WIRE 16 -1 (-3975 3050)(-4425 3050);
WIRE 16 -1 (-3975 2975)(-3975 3050);
WIRE 16 -1 (-4425 3050)(-4425 3100);
WIRE 16 -1 (-4425 3050)(-4425 2975);
WIRE 16 -1 (-3975 2650)(-4425 2650);
WIRE 16 -1 (-3525 2650)(-3975 2650);
WIRE 16 -1 (-3975 2650)(-3975 2775);
WIRE 16 -1 (-4425 2650)(-4425 2775);
WIRE 16 -1 (-3075 2650)(-3525 2650);
WIRE 16 -1 (-3525 2650)(-3525 2775);
WIRE 16 -1 (-2625 2650)(-3075 2650);
WIRE 16 -1 (-3075 2650)(-3075 2775);
WIRE 16 -1 (-2175 2650)(-2625 2650);
WIRE 16 -1 (-2625 2650)(-2625 2775);
WIRE 16 -1 (-1725 2650)(-2175 2650);
WIRE 16 -1 (-2175 2650)(-2175 2775);
WIRE 16 -1 (-1275 2650)(-1725 2650);
WIRE 16 -1 (-1725 2650)(-1725 2775);
WIRE 16 -1 (-825 2650)(-1275 2650);
WIRE 16 -1 (-1275 2650)(-1275 2775);
WIRE 16 -1 (-825 2650)(-425 2650);
WIRE 16 -1 (-825 2650)(-825 2775);
WIRE 16 -1 (-425 2650)(-425 2775);
WIRE 16 -1 (-425 2550)(-425 2650);
WIRE 16 -1 (-3975 2250)(-4425 2250);
WIRE 16 -1 (-3525 2250)(-3975 2250);
WIRE 16 -1 (-3975 2175)(-3975 2250);
WIRE 16 -1 (-4425 2250)(-4425 2300);
WIRE 16 -1 (-4425 2250)(-4425 2175);
WIRE 16 -1 (-3075 2250)(-3525 2250);
WIRE 16 -1 (-3525 2250)(-3525 2175);
WIRE 16 -1 (-2625 2250)(-3075 2250);
WIRE 16 -1 (-3075 2175)(-3075 2250);
WIRE 16 -1 (-2625 2175)(-2625 2250);
WIRE 16 -1 (-3975 1850)(-4425 1850);
WIRE 16 -1 (-3525 1850)(-3975 1850);
WIRE 16 -1 (-3975 1850)(-3975 1975);
WIRE 16 -1 (-4425 1850)(-4425 1975);
WIRE 16 -1 (-3075 1850)(-3525 1850);
WIRE 16 -1 (-3525 1850)(-3525 1975);
WIRE 16 -1 (-2625 1850)(-3075 1850);
WIRE 16 -1 (-3075 1850)(-3075 1975);
WIRE 16 -1 (-2625 1850)(-2625 1975);
WIRE 16 -1 (-2625 1775)(-2625 1850);
WIRE 16 3135 (-4600 800)(-100 800);
WIRE 16 3135 (-4600 800)(-4600 6100);
WIRE 16 3135 (-4600 6100)(-100 6100);
WIRE 16 3135 (-50 800)(-50 6100);
DOT 1 (-6300 3450);
DOT 1 (-9150 6100);
DOT 1 (-9150 800);
DOT 1 (-8550 1850);
DOT 1 (-9000 2250);
DOT 1 (-9000 3050);
DOT 1 (-8550 2250);
DOT 1 (-8550 2650);
DOT 1 (-8550 3050);
DOT 1 (-9000 3850);
DOT 1 (-8550 3450);
DOT 1 (-8550 3850);
DOT 1 (-9000 4650);
DOT 1 (-8550 4250);
DOT 1 (-8550 4650);
DOT 1 (-8550 5025);
DOT 1 (-9000 5425);
DOT 1 (-8550 5425);
DOT 1 (-8100 1850);
DOT 1 (-7650 1850);
DOT 1 (-7200 1850);
DOT 1 (-8100 2250);
DOT 1 (-8100 2650);
DOT 1 (-8100 3050);
DOT 1 (-7650 2250);
DOT 1 (-7650 2650);
DOT 1 (-7650 3050);
DOT 1 (-8100 3450);
DOT 1 (-8100 3850);
DOT 1 (-7650 3450);
DOT 1 (-7650 3850);
DOT 1 (-7200 2650);
DOT 1 (-7200 3050);
DOT 1 (-6750 2650);
DOT 1 (-6750 3050);
DOT 1 (-6300 2650);
DOT 1 (-6300 3050);
DOT 1 (-7200 3450);
DOT 1 (-6750 3450);
DOT 1 (-7200 3850);
DOT 1 (-6750 3850);
DOT 1 (-6300 3850);
DOT 1 (-5850 2650);
DOT 1 (-5850 3050);
DOT 1 (-5400 2650);
DOT 1 (-5400 3050);
DOT 1 (-5850 3450);
DOT 1 (-5850 3850);
DOT 1 (-5400 3450);
DOT 1 (-5400 3850);
DOT 1 (-5000 2650);
DOT 1 (-4425 2250);
DOT 1 (-4425 3050);
DOT 1 (-5000 3450);
DOT 1 (-4425 3850);
DOT 1 (-8100 4250);
DOT 1 (-8100 4650);
DOT 1 (-8100 5025);
DOT 1 (-7650 4250);
DOT 1 (-7650 4650);
DOT 1 (-7650 5025);
DOT 1 (-8100 5425);
DOT 1 (-7650 5425);
DOT 1 (-7200 4250);
DOT 1 (-6750 4250);
DOT 1 (-7200 4650);
DOT 1 (-7200 5025);
DOT 1 (-6750 4650);
DOT 1 (-6300 4250);
DOT 1 (-6300 4650);
DOT 1 (-6300 5025);
DOT 1 (-7200 5425);
DOT 1 (-6750 5425);
DOT 1 (-6300 5425);
DOT 1 (-5850 4250);
DOT 1 (-5850 4650);
DOT 1 (-5850 5025);
DOT 1 (-5400 4250);
DOT 1 (-5400 4650);
DOT 1 (-5400 5025);
DOT 1 (-5850 5425);
DOT 1 (-5400 5425);
DOT 1 (-5000 4250);
DOT 1 (-5000 5025);
DOT 1 (-4425 4650);
DOT 1 (-4425 5425);
DOT 1 (-3975 1850);
DOT 1 (-3525 1850);
DOT 1 (-3075 1850);
DOT 1 (-2625 1850);
DOT 1 (-3975 2250);
DOT 1 (-3975 2650);
DOT 1 (-3975 3050);
DOT 1 (-3525 2250);
DOT 1 (-3525 2650);
DOT 1 (-3525 3050);
DOT 1 (-3975 3450);
DOT 1 (-3975 3850);
DOT 1 (-3525 3450);
DOT 1 (-3525 3850);
DOT 1 (-3075 2250);
DOT 1 (-3075 2650);
DOT 1 (-3075 3050);
DOT 1 (-2625 2650);
DOT 1 (-2625 3050);
DOT 1 (-2175 2650);
DOT 1 (-2175 3050);
DOT 1 (-3075 3450);
DOT 1 (-2625 3450);
DOT 1 (-3075 3850);
DOT 1 (-2625 3850);
DOT 1 (-2175 3450);
DOT 1 (-2175 3850);
DOT 1 (-1725 2650);
DOT 1 (-1725 3050);
DOT 1 (-1275 2650);
DOT 1 (-1275 3050);
DOT 1 (-1725 3450);
DOT 1 (-1725 3850);
DOT 1 (-1275 3450);
DOT 1 (-1275 3850);
DOT 1 (-825 2650);
DOT 1 (-825 3050);
DOT 1 (-425 2650);
DOT 1 (-825 3450);
DOT 1 (-825 3850);
DOT 1 (-425 3450);
DOT 1 (-3975 4250);
DOT 1 (-3975 4650);
DOT 1 (-3975 5025);
DOT 1 (-3525 4250);
DOT 1 (-3525 4650);
DOT 1 (-3525 5025);
DOT 1 (-3975 5425);
DOT 1 (-3525 5425);
DOT 1 (-3075 4250);
DOT 1 (-2625 4250);
DOT 1 (-3075 4650);
DOT 1 (-3075 5025);
DOT 1 (-2625 4650);
DOT 1 (-2625 5025);
DOT 1 (-2175 4250);
DOT 1 (-2175 4650);
DOT 1 (-2175 5025);
DOT 1 (-3075 5425);
DOT 1 (-2625 5425);
DOT 1 (-2175 5425);
DOT 1 (-1725 4250);
DOT 1 (-1725 4650);
DOT 1 (-1725 5025);
DOT 1 (-1275 4250);
DOT 1 (-1275 4650);
DOT 1 (-1275 5025);
DOT 1 (-1725 5425);
DOT 1 (-1275 5425);
DOT 1 (-825 4250);
DOT 1 (-825 5025);
DOT 1 (-825 4650);
DOT 1 (-425 4250);
DOT 1 (-425 5025);
DOT 1 (-825 5425);
DOT 1 (-6750 5025);
FORCENOTE
PVDDCR_CPU1_P0: 45PCS 22UF ON BOT
(-4475 5850) 0;
DISPLAY LEFT (-4475 5850);
DISPLAY 2.510638 (-4475 5850);
PAINT WHITE (-4475 5850);
FORCENOTE
PVDDCR_CPU0_P0: 45PCS 22UF ON BOT
(-9125 5825) 0;
DISPLAY LEFT (-9125 5825);
DISPLAY 2.510638 (-9125 5825);
PAINT WHITE (-9125 5825);
FORCENOTE
5
(-7225 5525) 0;
DISPLAY LEFT (-7225 5525);
DISPLAY 1.021277 (-7225 5525);
PAINT SKYBLUE (-7225 5525);
FORCENOTE
5
(-2650 2350) 0;
DISPLAY LEFT (-2650 2350);
DISPLAY 1.021277 (-2650 2350);
PAINT SKYBLUE (-2650 2350);
FORCENOTE
5
(-2650 5550) 0;
DISPLAY LEFT (-2650 5550);
DISPLAY 1.021277 (-2650 5550);
PAINT SKYBLUE (-2650 5550);
FORCENOTE
10
(-475 5525) 0;
DISPLAY LEFT (-475 5525);
DISPLAY 1.021277 (-475 5525);
PAINT SKYBLUE (-475 5525);
FORCENOTE
10
(-5050 5525) 0;
DISPLAY LEFT (-5050 5525);
DISPLAY 1.021277 (-5050 5525);
PAINT SKYBLUE (-5050 5525);
QUIT
